G04*
G04 #@! TF.GenerationSoftware,Altium Limited,Altium Designer,23.7.1 (13)*
G04*
G04 Layer_Color=39423*
%FSLAX25Y25*%
%MOIN*%
G70*
G04*
G04 #@! TF.SameCoordinates,AF00DCEB-AC48-4C7C-91EA-99F42E284231*
G04*
G04*
G04 #@! TF.FilePolarity,Positive*
G04*
G01*
G75*
%ADD10C,0.00984*%
%ADD15C,0.00787*%
%ADD16C,0.00500*%
%ADD18C,0.01000*%
%ADD19C,0.00600*%
%ADD24C,0.00900*%
%ADD25C,0.00800*%
%ADD290R,1.38976X0.21654*%
G36*
X245079Y-270324D02*
X217520D01*
Y-248671D01*
X245079D01*
Y-270324D01*
D02*
G37*
%LPC*%
G36*
X230710Y-255553D02*
X229405D01*
X224367Y-263104D01*
Y-255553D01*
X223145D01*
Y-265158D01*
X224464D01*
X229488Y-257621D01*
Y-265158D01*
X230710D01*
Y-255553D01*
D02*
G37*
G36*
X236345Y-255386D02*
X236165D01*
X236067Y-255400D01*
X235970D01*
X235706Y-255428D01*
X235415Y-255470D01*
X235110Y-255539D01*
X234777Y-255622D01*
X234471Y-255733D01*
X234457D01*
X234430Y-255747D01*
X234388Y-255775D01*
X234332Y-255803D01*
X234194Y-255872D01*
X234013Y-255997D01*
X233805Y-256136D01*
X233597Y-256316D01*
X233402Y-256524D01*
X233222Y-256760D01*
Y-256774D01*
X233208Y-256788D01*
X233180Y-256830D01*
X233153Y-256872D01*
X233083Y-257010D01*
X233000Y-257191D01*
X232903Y-257413D01*
X232833Y-257677D01*
X232764Y-257954D01*
X232736Y-258260D01*
X233958Y-258357D01*
Y-258343D01*
Y-258315D01*
X233972Y-258273D01*
X233985Y-258204D01*
X234027Y-258051D01*
X234083Y-257843D01*
X234166Y-257621D01*
X234291Y-257399D01*
X234443Y-257191D01*
X234638Y-256996D01*
X234665Y-256982D01*
X234735Y-256927D01*
X234874Y-256844D01*
X235054Y-256760D01*
X235290Y-256677D01*
X235568Y-256594D01*
X235915Y-256538D01*
X236303Y-256524D01*
X236498D01*
X236581Y-256538D01*
X236692Y-256552D01*
X236942Y-256580D01*
X237220Y-256635D01*
X237497Y-256705D01*
X237761Y-256816D01*
X237872Y-256885D01*
X237983Y-256955D01*
X238011Y-256969D01*
X238066Y-257024D01*
X238149Y-257121D01*
X238233Y-257232D01*
X238330Y-257385D01*
X238413Y-257552D01*
X238469Y-257746D01*
X238496Y-257968D01*
Y-257996D01*
Y-258051D01*
X238482Y-258148D01*
X238455Y-258260D01*
X238413Y-258398D01*
X238344Y-258537D01*
X238261Y-258676D01*
X238136Y-258815D01*
X238122Y-258829D01*
X238052Y-258870D01*
X237997Y-258912D01*
X237941Y-258940D01*
X237858Y-258981D01*
X237761Y-259037D01*
X237636Y-259078D01*
X237497Y-259134D01*
X237344Y-259189D01*
X237164Y-259259D01*
X236970Y-259314D01*
X236748Y-259384D01*
X236498Y-259439D01*
X236220Y-259509D01*
X236206D01*
X236151Y-259523D01*
X236067Y-259536D01*
X235970Y-259564D01*
X235845Y-259592D01*
X235693Y-259634D01*
X235540Y-259675D01*
X235373Y-259717D01*
X235013Y-259814D01*
X234665Y-259911D01*
X234499Y-259967D01*
X234346Y-260022D01*
X234208Y-260064D01*
X234097Y-260119D01*
X234083D01*
X234055Y-260133D01*
X234013Y-260161D01*
X233958Y-260189D01*
X233805Y-260272D01*
X233625Y-260383D01*
X233416Y-260536D01*
X233208Y-260702D01*
X233014Y-260897D01*
X232847Y-261105D01*
X232833Y-261133D01*
X232778Y-261202D01*
X232722Y-261327D01*
X232639Y-261493D01*
X232570Y-261688D01*
X232500Y-261924D01*
X232459Y-262188D01*
X232445Y-262465D01*
Y-262590D01*
X232472Y-262743D01*
X232500Y-262937D01*
X232556Y-263159D01*
X232625Y-263395D01*
X232736Y-263645D01*
X232889Y-263909D01*
Y-263923D01*
X232903Y-263936D01*
X232972Y-264020D01*
X233069Y-264145D01*
X233208Y-264283D01*
X233389Y-264450D01*
X233611Y-264630D01*
X233860Y-264797D01*
X234152Y-264950D01*
X234166D01*
X234194Y-264964D01*
X234235Y-264977D01*
X234291Y-265005D01*
X234374Y-265033D01*
X234471Y-265075D01*
X234693Y-265130D01*
X234957Y-265199D01*
X235276Y-265269D01*
X235623Y-265311D01*
X235998Y-265324D01*
X236220D01*
X236331Y-265311D01*
X236456D01*
X236595Y-265297D01*
X236761Y-265283D01*
X237108Y-265227D01*
X237469Y-265172D01*
X237830Y-265075D01*
X238177Y-264950D01*
X238191D01*
X238219Y-264936D01*
X238261Y-264908D01*
X238316Y-264880D01*
X238482Y-264797D01*
X238677Y-264672D01*
X238899Y-264506D01*
X239135Y-264311D01*
X239357Y-264075D01*
X239565Y-263811D01*
Y-263798D01*
X239593Y-263770D01*
X239607Y-263728D01*
X239649Y-263673D01*
X239676Y-263603D01*
X239718Y-263520D01*
X239815Y-263312D01*
X239912Y-263048D01*
X239996Y-262757D01*
X240051Y-262423D01*
X240079Y-262076D01*
X238885Y-261965D01*
Y-261979D01*
Y-261993D01*
X238871Y-262035D01*
Y-262090D01*
X238843Y-262215D01*
X238802Y-262396D01*
X238746Y-262576D01*
X238691Y-262784D01*
X238594Y-262979D01*
X238496Y-263159D01*
X238482Y-263173D01*
X238441Y-263229D01*
X238371Y-263326D01*
X238261Y-263423D01*
X238122Y-263548D01*
X237969Y-263673D01*
X237761Y-263798D01*
X237539Y-263909D01*
X237525D01*
X237511Y-263923D01*
X237469Y-263936D01*
X237428Y-263950D01*
X237289Y-263992D01*
X237108Y-264047D01*
X236886Y-264103D01*
X236636Y-264145D01*
X236359Y-264172D01*
X236053Y-264186D01*
X235929D01*
X235790Y-264172D01*
X235623Y-264159D01*
X235429Y-264131D01*
X235207Y-264103D01*
X234985Y-264047D01*
X234777Y-263978D01*
X234749Y-263964D01*
X234679Y-263936D01*
X234582Y-263881D01*
X234457Y-263825D01*
X234332Y-263728D01*
X234194Y-263631D01*
X234055Y-263520D01*
X233944Y-263381D01*
X233930Y-263367D01*
X233902Y-263312D01*
X233860Y-263242D01*
X233805Y-263131D01*
X233750Y-263020D01*
X233708Y-262881D01*
X233680Y-262729D01*
X233666Y-262562D01*
Y-262548D01*
Y-262479D01*
X233680Y-262396D01*
X233694Y-262285D01*
X233736Y-262174D01*
X233777Y-262035D01*
X233847Y-261896D01*
X233944Y-261771D01*
X233958Y-261757D01*
X233999Y-261716D01*
X234055Y-261660D01*
X234152Y-261577D01*
X234263Y-261493D01*
X234416Y-261396D01*
X234596Y-261299D01*
X234804Y-261216D01*
X234818Y-261202D01*
X234888Y-261188D01*
X234999Y-261146D01*
X235068Y-261133D01*
X235165Y-261105D01*
X235262Y-261063D01*
X235387Y-261035D01*
X235526Y-260994D01*
X235693Y-260952D01*
X235859Y-260911D01*
X236053Y-260855D01*
X236276Y-260800D01*
X236512Y-260744D01*
X236526D01*
X236567Y-260730D01*
X236636Y-260716D01*
X236720Y-260688D01*
X236831Y-260661D01*
X236956Y-260633D01*
X237233Y-260550D01*
X237539Y-260453D01*
X237858Y-260355D01*
X238136Y-260258D01*
X238261Y-260203D01*
X238371Y-260147D01*
X238385D01*
X238399Y-260133D01*
X238482Y-260078D01*
X238608Y-260008D01*
X238746Y-259897D01*
X238913Y-259772D01*
X239079Y-259620D01*
X239246Y-259439D01*
X239385Y-259245D01*
X239399Y-259217D01*
X239440Y-259148D01*
X239496Y-259037D01*
X239551Y-258898D01*
X239607Y-258717D01*
X239662Y-258509D01*
X239704Y-258287D01*
X239718Y-258051D01*
Y-258037D01*
Y-258024D01*
Y-257982D01*
Y-257926D01*
X239690Y-257788D01*
X239662Y-257607D01*
X239621Y-257399D01*
X239551Y-257163D01*
X239454Y-256927D01*
X239315Y-256691D01*
Y-256677D01*
X239301Y-256663D01*
X239232Y-256580D01*
X239135Y-256469D01*
X239010Y-256330D01*
X238843Y-256177D01*
X238635Y-256011D01*
X238385Y-255858D01*
X238108Y-255719D01*
X238094D01*
X238066Y-255706D01*
X238024Y-255692D01*
X237969Y-255664D01*
X237900Y-255636D01*
X237802Y-255608D01*
X237594Y-255553D01*
X237331Y-255497D01*
X237025Y-255442D01*
X236706Y-255400D01*
X236345Y-255386D01*
D02*
G37*
%LPD*%
D10*
X585322Y-281567D02*
G03*
X585322Y-281567I-492J0D01*
G01*
D15*
X561877Y-282487D02*
G03*
X561877Y-282487I-394J0D01*
G01*
X540571Y-271732D02*
G03*
X540571Y-271732I-394J0D01*
G01*
X599119Y-289052D02*
Y-282467D01*
X593322Y-289052D02*
Y-282467D01*
X541715Y-274434D02*
Y-269268D01*
X547227Y-274434D02*
Y-269268D01*
X578110Y-280075D02*
Y-274909D01*
X583622Y-280075D02*
Y-274909D01*
X583765Y-288658D02*
Y-282074D01*
X577967Y-288658D02*
Y-282074D01*
X554353Y-283511D02*
X559519D01*
X554353Y-277999D02*
X559519D01*
X587192Y-283634D02*
X592113D01*
X587231Y-276351D02*
X592152D01*
X593464Y-280862D02*
Y-275696D01*
X598976Y-280862D02*
Y-275696D01*
X480628Y-302970D02*
Y-297804D01*
X475116Y-302970D02*
Y-297804D01*
X477732Y-262992D02*
X482898D01*
X477732Y-268504D02*
X482898D01*
X187008Y-97071D02*
Y-91905D01*
X192520Y-97071D02*
Y-91905D01*
X148995Y1361D02*
Y6527D01*
X154506Y1361D02*
Y6527D01*
X494661Y-249606D02*
X499827D01*
X494661Y-255118D02*
X499827D01*
X505094Y-262892D02*
X510260D01*
X505094Y-257380D02*
X510260D01*
X495055Y-257087D02*
X500221D01*
X495055Y-262598D02*
X500221D01*
X563362Y-258363D02*
X568528D01*
X563362Y-263875D02*
X568528D01*
X570744Y-263878D02*
X575910D01*
X570744Y-258366D02*
X575910D01*
X212205Y173D02*
Y5339D01*
X206693Y173D02*
Y5339D01*
X206594Y-5536D02*
Y-370D01*
X201083Y-5536D02*
Y-370D01*
X216929Y-5733D02*
Y-567D01*
X211417Y-5733D02*
Y-567D01*
X201781Y-77583D02*
Y-72417D01*
X207293Y-77583D02*
Y-72417D01*
X211417Y-77386D02*
Y-72220D01*
X216929Y-77386D02*
Y-72220D01*
X408268Y-126772D02*
X412205D01*
X408268Y-132327D02*
X412205D01*
X412456Y-127308D02*
X419040D01*
X412456Y-121511D02*
X419040D01*
X426544Y-135576D02*
X433299D01*
X426544Y-129779D02*
X433299D01*
X54025Y-35531D02*
Y-31594D01*
X59580Y-35531D02*
Y-31594D01*
X109700Y-19040D02*
X116284D01*
X109700Y-13243D02*
X116284D01*
X92377Y-80064D02*
X98962D01*
X92377Y-74267D02*
X98962D01*
X105905Y-48782D02*
Y-43616D01*
X111417Y-48782D02*
Y-43616D01*
X279134Y-197859D02*
Y-192693D01*
X284646Y-197859D02*
Y-192693D01*
X336787Y-295669D02*
X341953D01*
X336787Y-290158D02*
X341953D01*
X317889Y-296457D02*
X323055D01*
X317889Y-290945D02*
X323055D01*
X323008Y-242520D02*
X328173D01*
X323008Y-237008D02*
X328173D01*
X375370Y-230217D02*
X380536D01*
X375370Y-235728D02*
X380536D01*
X556595Y-327461D02*
X557579D01*
X556595Y-333169D02*
X557579D01*
X532727Y-331692D02*
X533711D01*
X532727Y-325983D02*
X533711D01*
X565650Y-312697D02*
X566634D01*
X565650Y-306988D02*
X566634D01*
X532727Y-315127D02*
X533711D01*
X532727Y-309418D02*
X533711D01*
X121555Y-33366D02*
X122539D01*
X121555Y-39075D02*
X122539D01*
X124911Y-77429D02*
X125896D01*
X124911Y-71720D02*
X125896D01*
X147541Y-73927D02*
X148525D01*
X147541Y-68218D02*
X148525D01*
X151486Y-46210D02*
Y-45226D01*
X145778Y-46210D02*
Y-45226D01*
X610409Y-235827D02*
X615575D01*
X610409Y-241339D02*
X615575D01*
X611743Y-228346D02*
X616909D01*
X611743Y-233858D02*
X616909D01*
X611767Y-300098D02*
X616777D01*
X611767Y-305413D02*
X616777D01*
X382413Y-131791D02*
X389500D01*
X382413Y-138287D02*
X389500D01*
X67776Y-59517D02*
Y-52430D01*
X61279Y-59517D02*
Y-52430D01*
X93164Y-50143D02*
Y-43558D01*
X98962Y-50143D02*
Y-43558D01*
X105217Y-50000D02*
Y-42913D01*
X98721Y-50000D02*
Y-42913D01*
X607480Y-61713D02*
X614567D01*
X607480Y-68209D02*
X614567D01*
X148909Y-126870D02*
X153919D01*
X148909Y-121555D02*
X153919D01*
X161713Y-105118D02*
Y-98032D01*
X168209Y-105118D02*
Y-98032D01*
X156048Y-104867D02*
Y-98282D01*
X150251Y-104867D02*
Y-98282D01*
X155905Y-102573D02*
Y-97407D01*
X161417Y-102573D02*
Y-97407D01*
D16*
X565420Y-284377D02*
X570145D01*
X565420Y-274692D02*
X570145D01*
X531516Y-269843D02*
X536240D01*
X531516Y-279528D02*
X536240D01*
D18*
X240339Y-207779D02*
X236273D01*
X238306D01*
Y-213877D01*
X234241D02*
X232208D01*
X233224D01*
Y-209812D01*
X234241D01*
X229159Y-213877D02*
Y-209812D01*
X228142D01*
X227126Y-210828D01*
Y-213877D01*
Y-210828D01*
X226110Y-209812D01*
X225094Y-210828D01*
Y-213877D01*
X220012D02*
X222044D01*
X223061Y-212861D01*
Y-210828D01*
X222044Y-209812D01*
X220012D01*
X218995Y-210828D01*
Y-211845D01*
X223061D01*
X206799Y-208796D02*
X207816Y-207779D01*
X209848D01*
X210865Y-208796D01*
Y-212861D01*
X209848Y-213877D01*
X207816D01*
X206799Y-212861D01*
X203750Y-209812D02*
X201718D01*
X200701Y-210828D01*
Y-213877D01*
X203750D01*
X204767Y-212861D01*
X203750Y-211845D01*
X200701D01*
X198669Y-209812D02*
Y-213877D01*
Y-211845D01*
X197652Y-210828D01*
X196636Y-209812D01*
X195620D01*
X188505Y-207779D02*
Y-213877D01*
X191554D01*
X192571Y-212861D01*
Y-210828D01*
X191554Y-209812D01*
X188505D01*
X180375Y-207779D02*
Y-211845D01*
X178342Y-213877D01*
X176309Y-211845D01*
Y-207779D01*
X174277Y-212861D02*
X173260Y-213877D01*
X171228D01*
X170211Y-212861D01*
Y-208796D01*
X171228Y-207779D01*
X173260D01*
X174277Y-208796D01*
Y-209812D01*
X173260Y-210828D01*
X170211D01*
X240339Y-223595D02*
Y-217497D01*
X238306Y-219530D01*
X236273Y-217497D01*
Y-223595D01*
X234241D02*
X232208D01*
X233224D01*
Y-219530D01*
X234241D01*
X229159Y-223595D02*
Y-217497D01*
Y-221562D02*
X226110Y-219530D01*
X229159Y-221562D02*
X226110Y-223595D01*
X220012D02*
X222044D01*
X223061Y-222579D01*
Y-220546D01*
X222044Y-219530D01*
X220012D01*
X218995Y-220546D01*
Y-221562D01*
X223061D01*
X210865Y-217497D02*
Y-223595D01*
X206799D01*
X203750Y-219530D02*
X201718D01*
X200701Y-220546D01*
Y-223595D01*
X203750D01*
X204767Y-222579D01*
X203750Y-221562D01*
X200701D01*
X198669Y-223595D02*
Y-219530D01*
X197652D01*
X196636Y-220546D01*
Y-223595D01*
Y-220546D01*
X195620Y-219530D01*
X194603Y-220546D01*
Y-223595D01*
X192571Y-217497D02*
Y-223595D01*
X189522D01*
X188505Y-222579D01*
Y-221562D01*
Y-220546D01*
X189522Y-219530D01*
X192571D01*
X183424Y-223595D02*
X185456D01*
X186473Y-222579D01*
Y-220546D01*
X185456Y-219530D01*
X183424D01*
X182407Y-220546D01*
Y-221562D01*
X186473D01*
X179358Y-218513D02*
Y-219530D01*
X180375D01*
X178342D01*
X179358D01*
Y-222579D01*
X178342Y-223595D01*
X174277Y-219530D02*
X172244D01*
X171228Y-220546D01*
Y-223595D01*
X174277D01*
X175293Y-222579D01*
X174277Y-221562D01*
X171228D01*
X240339Y-233313D02*
Y-229247D01*
X238306Y-227215D01*
X236273Y-229247D01*
Y-233313D01*
Y-230264D01*
X240339D01*
X234241Y-227215D02*
Y-233313D01*
Y-230264D01*
X233224Y-229247D01*
X231191D01*
X230175Y-230264D01*
Y-233313D01*
X228142D02*
Y-229247D01*
X227126D01*
X226110Y-230264D01*
Y-233313D01*
Y-230264D01*
X225094Y-229247D01*
X224077Y-230264D01*
Y-233313D01*
X221028Y-229247D02*
X218995D01*
X217979Y-230264D01*
Y-233313D01*
X221028D01*
X222044Y-232296D01*
X221028Y-231280D01*
X217979D01*
X211881Y-227215D02*
Y-233313D01*
X214930D01*
X215947Y-232296D01*
Y-230264D01*
X214930Y-229247D01*
X211881D01*
X203750Y-227215D02*
Y-233313D01*
X200701D01*
X199685Y-232296D01*
Y-231280D01*
X200701Y-230264D01*
X203750D01*
X200701D01*
X199685Y-229247D01*
Y-228231D01*
X200701Y-227215D01*
X203750D01*
X197652Y-229247D02*
Y-232296D01*
X196636Y-233313D01*
X193587D01*
Y-234329D01*
X194603Y-235345D01*
X195620D01*
X193587Y-233313D02*
Y-229247D01*
X190538D02*
X188505D01*
X187489Y-230264D01*
Y-233313D01*
X190538D01*
X191554Y-232296D01*
X190538Y-231280D01*
X187489D01*
X183424Y-235345D02*
X182407D01*
X181391Y-234329D01*
Y-229247D01*
X184440D01*
X185456Y-230264D01*
Y-232296D01*
X184440Y-233313D01*
X181391D01*
X178342D02*
X176309D01*
X175293Y-232296D01*
Y-230264D01*
X176309Y-229247D01*
X178342D01*
X179358Y-230264D01*
Y-232296D01*
X178342Y-233313D01*
X173260Y-229247D02*
Y-232296D01*
X172244Y-233313D01*
X171228Y-232296D01*
X170211Y-233313D01*
X169195Y-232296D01*
Y-229247D01*
X167162Y-233313D02*
X165129D01*
X166146D01*
Y-229247D01*
X167162D01*
X236273Y-238965D02*
X238306D01*
X237290D01*
Y-244047D01*
X238306Y-245063D01*
X239322D01*
X240339Y-244047D01*
X234241Y-240998D02*
Y-244047D01*
X233224Y-245063D01*
X230175D01*
Y-240998D01*
X228142Y-245063D02*
X226110D01*
X227126D01*
Y-238965D01*
X228142D01*
X223061Y-245063D02*
X221028D01*
X222044D01*
Y-240998D01*
X223061D01*
X216963D02*
X214930D01*
X213914Y-242014D01*
Y-245063D01*
X216963D01*
X217979Y-244047D01*
X216963Y-243030D01*
X213914D01*
X211881Y-245063D02*
Y-240998D01*
X208832D01*
X207816Y-242014D01*
Y-245063D01*
X195620Y-239981D02*
X196636Y-238965D01*
X198669D01*
X199685Y-239981D01*
Y-240998D01*
X198669Y-242014D01*
X196636D01*
X195620Y-243030D01*
Y-244047D01*
X196636Y-245063D01*
X198669D01*
X199685Y-244047D01*
X192571Y-239981D02*
Y-240998D01*
X193587D01*
X191554D01*
X192571D01*
Y-244047D01*
X191554Y-245063D01*
X188505D02*
Y-244047D01*
X187489D01*
Y-245063D01*
X188505D01*
X173260Y-238965D02*
X175293D01*
X174277D01*
Y-244047D01*
X175293Y-245063D01*
X176309D01*
X177326Y-244047D01*
X170211Y-240998D02*
X168179D01*
X167162Y-242014D01*
Y-245063D01*
X170211D01*
X171228Y-244047D01*
X170211Y-243030D01*
X167162D01*
X165129Y-245063D02*
Y-240998D01*
X164113D01*
X163097Y-242014D01*
Y-245063D01*
Y-242014D01*
X162081Y-240998D01*
X161064Y-242014D01*
Y-245063D01*
X155982D02*
X158015D01*
X159031Y-244047D01*
Y-242014D01*
X158015Y-240998D01*
X155982D01*
X154966Y-242014D01*
Y-243030D01*
X159031D01*
X152934Y-245063D02*
X149884D01*
X148868Y-244047D01*
X149884Y-243030D01*
X151917D01*
X152934Y-242014D01*
X151917Y-240998D01*
X148868D01*
X51451Y-155015D02*
X57449D01*
Y-152016D01*
X56450Y-151017D01*
X54450D01*
X53451Y-152016D01*
Y-155015D01*
Y-153016D02*
X51451Y-151017D01*
Y-149017D02*
Y-147018D01*
Y-148018D01*
X57449D01*
X56450Y-149017D01*
Y-144019D02*
X57449Y-143019D01*
Y-141020D01*
X56450Y-140020D01*
X55450D01*
X54450Y-141020D01*
X53451Y-140020D01*
X52451D01*
X51451Y-141020D01*
Y-143019D01*
X52451Y-144019D01*
X53451D01*
X54450Y-143019D01*
X55450Y-144019D01*
X56450D01*
X54450Y-143019D02*
Y-141020D01*
X57449Y-134022D02*
X56450Y-136022D01*
X54450Y-138021D01*
X52451D01*
X51451Y-137021D01*
Y-135022D01*
X52451Y-134022D01*
X53451D01*
X54450Y-135022D01*
Y-138021D01*
X450351Y-155181D02*
X456349D01*
Y-152182D01*
X455349Y-151182D01*
X453350D01*
X452350Y-152182D01*
Y-155181D01*
Y-153181D02*
X450351Y-151182D01*
Y-149183D02*
Y-147183D01*
Y-148183D01*
X456349D01*
X455349Y-149183D01*
Y-144184D02*
X456349Y-143185D01*
Y-141185D01*
X455349Y-140186D01*
X454350D01*
X453350Y-141185D01*
X452350Y-140186D01*
X451350D01*
X450351Y-141185D01*
Y-143185D01*
X451350Y-144184D01*
X452350D01*
X453350Y-143185D01*
X454350Y-144184D01*
X455349D01*
X453350Y-143185D02*
Y-141185D01*
X456349Y-134187D02*
Y-138186D01*
X453350D01*
X454350Y-136187D01*
Y-135187D01*
X453350Y-134187D01*
X451350D01*
X450351Y-135187D01*
Y-137187D01*
X451350Y-138186D01*
X436453Y-152713D02*
Y-158711D01*
X439452D01*
X440451Y-157711D01*
Y-155712D01*
X439452Y-154712D01*
X436453D01*
X438452D02*
X440451Y-152713D01*
X442451D02*
X444450D01*
X443450D01*
Y-158711D01*
X442451Y-157711D01*
X447449D02*
X448449Y-158711D01*
X450448D01*
X451448Y-157711D01*
Y-156712D01*
X450448Y-155712D01*
X451448Y-154712D01*
Y-153713D01*
X450448Y-152713D01*
X448449D01*
X447449Y-153713D01*
Y-154712D01*
X448449Y-155712D01*
X447449Y-156712D01*
Y-157711D01*
X448449Y-155712D02*
X450448D01*
X456446Y-152713D02*
Y-158711D01*
X453447Y-155712D01*
X457446D01*
X440882Y-152713D02*
Y-158711D01*
X443881D01*
X444881Y-157711D01*
Y-155712D01*
X443881Y-154712D01*
X440882D01*
X442882D02*
X444881Y-152713D01*
X446880D02*
X448880D01*
X447880D01*
Y-158711D01*
X446880Y-157711D01*
X451879D02*
X452878Y-158711D01*
X454878D01*
X455877Y-157711D01*
Y-156712D01*
X454878Y-155712D01*
X455877Y-154712D01*
Y-153713D01*
X454878Y-152713D01*
X452878D01*
X451879Y-153713D01*
Y-154712D01*
X452878Y-155712D01*
X451879Y-156712D01*
Y-157711D01*
X452878Y-155712D02*
X454878D01*
X457877Y-157711D02*
X458877Y-158711D01*
X460876D01*
X461875Y-157711D01*
Y-156712D01*
X460876Y-155712D01*
X459876D01*
X460876D01*
X461875Y-154712D01*
Y-153713D01*
X460876Y-152713D01*
X458877D01*
X457877Y-153713D01*
X562893Y-221053D02*
Y-224052D01*
X560893D01*
X557894Y-221053D02*
X559894D01*
Y-224052D01*
X557894D01*
X559894Y-222552D02*
X558894D01*
X556895Y-221053D02*
Y-224052D01*
X555395D01*
X554895Y-223552D01*
Y-221553D01*
X555395Y-221053D01*
X556895D01*
X549897Y-224052D02*
X550897Y-223052D01*
Y-222053D01*
X549897Y-221053D01*
X548397D02*
Y-224052D01*
X546898D01*
X546398Y-223552D01*
Y-221553D01*
X546898Y-221053D01*
X548397D01*
X543399Y-224052D02*
X545398D01*
X543399Y-222053D01*
Y-221553D01*
X543899Y-221053D01*
X544899D01*
X545398Y-221553D01*
X540400Y-224052D02*
X542399D01*
X540400Y-222053D01*
Y-221553D01*
X540900Y-221053D01*
X541900D01*
X542399Y-221553D01*
X539400Y-224052D02*
X538401Y-223052D01*
Y-222053D01*
X539400Y-221053D01*
X532403D02*
X533402D01*
X533902Y-221553D01*
Y-223552D01*
X533402Y-224052D01*
X532403D01*
X531903Y-223552D01*
Y-221553D01*
X532403Y-221053D01*
X530903Y-224052D02*
Y-222053D01*
X529404D01*
X528904Y-222552D01*
Y-224052D01*
X524405D02*
Y-221553D01*
Y-222552D01*
X524905D01*
X523905D01*
X524405D01*
Y-221553D01*
X523905Y-221053D01*
X521906Y-224052D02*
X520906D01*
X520406Y-223552D01*
Y-222552D01*
X520906Y-222053D01*
X521906D01*
X522406Y-222552D01*
Y-223552D01*
X521906Y-224052D01*
X519407Y-222053D02*
Y-224052D01*
Y-223052D01*
X518907Y-222552D01*
X518407Y-222053D01*
X517907D01*
X511410Y-221553D02*
X511909Y-221053D01*
X512909D01*
X513409Y-221553D01*
Y-222053D01*
X512909Y-222552D01*
X511909D01*
X511410Y-223052D01*
Y-223552D01*
X511909Y-224052D01*
X512909D01*
X513409Y-223552D01*
X508410Y-221053D02*
X510410D01*
Y-224052D01*
X508410D01*
X510410Y-222552D02*
X509410D01*
X504412Y-224052D02*
Y-221053D01*
X502912D01*
X502412Y-221553D01*
Y-222552D01*
X502912Y-223052D01*
X504412D01*
X501413Y-224052D02*
Y-221053D01*
X499913D01*
X499413Y-221553D01*
Y-222552D01*
X499913Y-223052D01*
X501413D01*
X496414Y-221553D02*
X496914Y-221053D01*
X497914D01*
X498414Y-221553D01*
Y-222053D01*
X497914Y-222552D01*
X496914D01*
X496414Y-223052D01*
Y-223552D01*
X496914Y-224052D01*
X497914D01*
X498414Y-223552D01*
X491416Y-224052D02*
X492416Y-223052D01*
Y-222053D01*
X491416Y-221053D01*
X489916Y-224052D02*
Y-221053D01*
X488917Y-222053D01*
X487917Y-221053D01*
Y-224052D01*
X486417D02*
X485418D01*
X484918Y-223552D01*
Y-222552D01*
X485418Y-222053D01*
X486417D01*
X486917Y-222552D01*
Y-223552D01*
X486417Y-224052D01*
X483918D02*
X482419D01*
X481919Y-223552D01*
X482419Y-223052D01*
X483419D01*
X483918Y-222552D01*
X483419Y-222053D01*
X481919D01*
X480419Y-221553D02*
Y-222053D01*
X480919D01*
X479920D01*
X480419D01*
Y-223552D01*
X479920Y-224052D01*
X473422Y-222053D02*
X474921D01*
X475421Y-222552D01*
Y-223552D01*
X474921Y-224052D01*
X473422D01*
X471922D02*
X470923D01*
X470423Y-223552D01*
Y-222552D01*
X470923Y-222053D01*
X471922D01*
X472422Y-222552D01*
Y-223552D01*
X471922Y-224052D01*
X469423D02*
Y-222053D01*
X468923D01*
X468423Y-222552D01*
Y-224052D01*
Y-222552D01*
X467923Y-222053D01*
X467424Y-222552D01*
Y-224052D01*
X466424D02*
Y-222053D01*
X465924D01*
X465424Y-222552D01*
Y-224052D01*
Y-222552D01*
X464924Y-222053D01*
X464425Y-222552D01*
Y-224052D01*
X462925D02*
X461926D01*
X461426Y-223552D01*
Y-222552D01*
X461926Y-222053D01*
X462925D01*
X463425Y-222552D01*
Y-223552D01*
X462925Y-224052D01*
X460426D02*
Y-222053D01*
X458926D01*
X458427Y-222552D01*
Y-224052D01*
X457427D02*
X456427Y-223052D01*
Y-222053D01*
X457427Y-221053D01*
X561610Y-225465D02*
X562609D01*
X563109Y-225964D01*
Y-227964D01*
X562609Y-228464D01*
X561610D01*
X561110Y-227964D01*
Y-225964D01*
X561610Y-225465D01*
X559610Y-228464D02*
Y-225964D01*
Y-226964D01*
X560110D01*
X559111D01*
X559610D01*
Y-225964D01*
X559111Y-225465D01*
X557111Y-228464D02*
Y-225964D01*
Y-226964D01*
X557611D01*
X556611D01*
X557111D01*
Y-225964D01*
X556611Y-225465D01*
X551613Y-228464D02*
Y-225964D01*
Y-226964D01*
X552113D01*
X551113D01*
X551613D01*
Y-225964D01*
X551113Y-225465D01*
X549114Y-228464D02*
X548114D01*
X547614Y-227964D01*
Y-226964D01*
X548114Y-226464D01*
X549114D01*
X549614Y-226964D01*
Y-227964D01*
X549114Y-228464D01*
X546615Y-226464D02*
Y-228464D01*
Y-227464D01*
X546115Y-226964D01*
X545615Y-226464D01*
X545115D01*
X540617Y-225465D02*
Y-228464D01*
X539117D01*
X538617Y-227964D01*
Y-225964D01*
X539117Y-225465D01*
X540617D01*
X537617Y-228464D02*
X536618D01*
X537118D01*
Y-226464D01*
X537617D01*
X534619Y-228464D02*
Y-225964D01*
Y-226964D01*
X535118D01*
X534119D01*
X534619D01*
Y-225964D01*
X534119Y-225465D01*
X532119Y-228464D02*
Y-225964D01*
Y-226964D01*
X532619D01*
X531620D01*
X532119D01*
Y-225964D01*
X531620Y-225465D01*
X527121Y-228464D02*
Y-225465D01*
X525621D01*
X525122Y-225964D01*
Y-226964D01*
X525621Y-227464D01*
X527121D01*
X524122Y-228464D02*
Y-225465D01*
X522622D01*
X522122Y-225964D01*
Y-226964D01*
X522622Y-227464D01*
X524122D01*
X519124Y-225964D02*
X519623Y-225465D01*
X520623D01*
X521123Y-225964D01*
Y-226464D01*
X520623Y-226964D01*
X519623D01*
X519124Y-227464D01*
Y-227964D01*
X519623Y-228464D01*
X520623D01*
X521123Y-227964D01*
X514125Y-228464D02*
X515125Y-227464D01*
Y-226464D01*
X514125Y-225465D01*
X510626Y-225964D02*
X511126Y-225465D01*
X512126D01*
X512626Y-225964D01*
Y-226464D01*
X512126Y-226964D01*
X511126D01*
X510626Y-227464D01*
Y-227964D01*
X511126Y-228464D01*
X512126D01*
X512626Y-227964D01*
X509627Y-228464D02*
Y-226464D01*
X508627Y-225465D01*
X507627Y-226464D01*
Y-228464D01*
Y-226964D01*
X509627D01*
X504628Y-225465D02*
X506628D01*
Y-226964D01*
X505628Y-226464D01*
X505128D01*
X504628Y-226964D01*
Y-227964D01*
X505128Y-228464D01*
X506128D01*
X506628Y-227964D01*
X503628Y-225964D02*
X503129Y-225465D01*
X502129D01*
X501629Y-225964D01*
Y-226464D01*
X502129Y-226964D01*
X502629D01*
X502129D01*
X501629Y-227464D01*
Y-227964D01*
X502129Y-228464D01*
X503129D01*
X503628Y-227964D01*
X564748Y-196395D02*
Y-199394D01*
X562749D01*
X559750Y-196395D02*
X561749D01*
Y-199394D01*
X559750D01*
X561749Y-197894D02*
X560749D01*
X558750Y-196395D02*
Y-199394D01*
X557250D01*
X556751Y-198894D01*
Y-196895D01*
X557250Y-196395D01*
X558750D01*
X551752Y-199394D02*
X552752Y-198394D01*
Y-197394D01*
X551752Y-196395D01*
X550253D02*
Y-199394D01*
X548753D01*
X548253Y-198894D01*
Y-196895D01*
X548753Y-196395D01*
X550253D01*
X545254Y-199394D02*
X547254D01*
X545254Y-197394D01*
Y-196895D01*
X545754Y-196395D01*
X546754D01*
X547254Y-196895D01*
X544255Y-199394D02*
X543255D01*
X543755D01*
Y-196395D01*
X544255Y-196895D01*
X541755Y-199394D02*
X540756Y-198394D01*
Y-197394D01*
X541755Y-196395D01*
X534758D02*
X535757D01*
X536257Y-196895D01*
Y-198894D01*
X535757Y-199394D01*
X534758D01*
X534258Y-198894D01*
Y-196895D01*
X534758Y-196395D01*
X532758Y-199394D02*
Y-196895D01*
Y-197894D01*
X533258D01*
X532259D01*
X532758D01*
Y-196895D01*
X532259Y-196395D01*
X530259Y-199394D02*
Y-196895D01*
Y-197894D01*
X530759D01*
X529759D01*
X530259D01*
Y-196895D01*
X529759Y-196395D01*
X524761Y-199394D02*
Y-196895D01*
Y-197894D01*
X525261D01*
X524261D01*
X524761D01*
Y-196895D01*
X524261Y-196395D01*
X522262Y-199394D02*
X521262D01*
X520762Y-198894D01*
Y-197894D01*
X521262Y-197394D01*
X522262D01*
X522762Y-197894D01*
Y-198894D01*
X522262Y-199394D01*
X519763Y-197394D02*
Y-199394D01*
Y-198394D01*
X519263Y-197894D01*
X518763Y-197394D01*
X518263D01*
X513764Y-196395D02*
Y-198894D01*
X513265Y-199394D01*
X512265D01*
X511765Y-198894D01*
Y-196395D01*
X508766Y-196895D02*
X509266Y-196395D01*
X510266D01*
X510766Y-196895D01*
Y-197394D01*
X510266Y-197894D01*
X509266D01*
X508766Y-198394D01*
Y-198894D01*
X509266Y-199394D01*
X510266D01*
X510766Y-198894D01*
X507766Y-196395D02*
Y-199394D01*
X506267D01*
X505767Y-198894D01*
Y-198394D01*
X506267Y-197894D01*
X507766D01*
X506267D01*
X505767Y-197394D01*
Y-196895D01*
X506267Y-196395D01*
X507766D01*
X499769D02*
X501768D01*
Y-197894D01*
X500769D01*
X501768D01*
Y-199394D01*
X498769Y-196395D02*
X496770D01*
X497770D01*
Y-199394D01*
X495770Y-196395D02*
Y-199394D01*
X494271D01*
X493771Y-198894D01*
Y-196895D01*
X494271Y-196395D01*
X495770D01*
X492771D02*
X491772D01*
X492272D01*
Y-199394D01*
X492771D01*
X491772D01*
X485774D02*
X487273Y-197894D01*
X485774Y-196395D01*
X484274Y-197894D02*
X482275D01*
X481275Y-199394D02*
X479775Y-197894D01*
X481275Y-196395D01*
X473777D02*
X475777D01*
Y-197894D01*
X474777D01*
X475777D01*
Y-199394D01*
X472778D02*
Y-196395D01*
X471278D01*
X470778Y-196895D01*
Y-197894D01*
X471278Y-198394D01*
X472778D01*
X467779Y-196895D02*
X468279Y-196395D01*
X469279D01*
X469779Y-196895D01*
Y-198894D01*
X469279Y-199394D01*
X468279D01*
X467779Y-198894D01*
Y-197894D01*
X468779D01*
X466780Y-199394D02*
Y-197394D01*
X465780Y-196395D01*
X464780Y-197394D01*
Y-199394D01*
Y-197894D01*
X466780D01*
X564748Y-206812D02*
Y-209811D01*
X562749D01*
X559750Y-206812D02*
X561749D01*
Y-209811D01*
X559750D01*
X561749Y-208312D02*
X560749D01*
X558750Y-206812D02*
Y-209811D01*
X557250D01*
X556751Y-209312D01*
Y-207312D01*
X557250Y-206812D01*
X558750D01*
X551752Y-209811D02*
X552752Y-208812D01*
Y-207812D01*
X551752Y-206812D01*
X550253D02*
Y-209811D01*
X548753D01*
X548253Y-209312D01*
Y-207312D01*
X548753Y-206812D01*
X550253D01*
X545254Y-209811D02*
X547254D01*
X545254Y-207812D01*
Y-207312D01*
X545754Y-206812D01*
X546754D01*
X547254Y-207312D01*
X544255Y-209811D02*
X543255D01*
X543755D01*
Y-206812D01*
X544255Y-207312D01*
X541755Y-209811D02*
X540756Y-208812D01*
Y-207812D01*
X541755Y-206812D01*
X536257D02*
Y-209811D01*
X534258D01*
X533258D02*
X532259D01*
X532758D01*
Y-207812D01*
X533258D01*
X530259Y-207312D02*
Y-207812D01*
X530759D01*
X529759D01*
X530259D01*
Y-209312D01*
X529759Y-209811D01*
X524761D02*
Y-207312D01*
Y-208312D01*
X525261D01*
X524261D01*
X524761D01*
Y-207312D01*
X524261Y-206812D01*
X522262Y-209811D02*
X521262D01*
X520762Y-209312D01*
Y-208312D01*
X521262Y-207812D01*
X522262D01*
X522762Y-208312D01*
Y-209312D01*
X522262Y-209811D01*
X519763Y-207812D02*
Y-209811D01*
Y-208812D01*
X519263Y-208312D01*
X518763Y-207812D01*
X518263D01*
X513764Y-206812D02*
Y-209312D01*
X513265Y-209811D01*
X512265D01*
X511765Y-209312D01*
Y-206812D01*
X508766Y-207312D02*
X509266Y-206812D01*
X510266D01*
X510766Y-207312D01*
Y-207812D01*
X510266Y-208312D01*
X509266D01*
X508766Y-208812D01*
Y-209312D01*
X509266Y-209811D01*
X510266D01*
X510766Y-209312D01*
X507766Y-206812D02*
Y-209811D01*
X506267D01*
X505767Y-209312D01*
Y-208812D01*
X506267Y-208312D01*
X507766D01*
X506267D01*
X505767Y-207812D01*
Y-207312D01*
X506267Y-206812D01*
X507766D01*
X499769D02*
X501768D01*
Y-208312D01*
X500769D01*
X501768D01*
Y-209811D01*
X498769Y-206812D02*
X496770D01*
X497770D01*
Y-209811D01*
X495770Y-206812D02*
Y-209811D01*
X494271D01*
X493771Y-209312D01*
Y-207312D01*
X494271Y-206812D01*
X495770D01*
X492771D02*
X491772D01*
X492272D01*
Y-209811D01*
X492771D01*
X491772D01*
X485774D02*
X487273Y-208312D01*
X485774Y-206812D01*
X484274Y-208312D02*
X482275D01*
X481275Y-209811D02*
X479775Y-208312D01*
X481275Y-206812D01*
X473777Y-207312D02*
X474277Y-206812D01*
X475277D01*
X475777Y-207312D01*
Y-209312D01*
X475277Y-209811D01*
X474277D01*
X473777Y-209312D01*
Y-208312D01*
X474777D01*
X472778Y-209811D02*
Y-206812D01*
X471278D01*
X470778Y-207312D01*
Y-208312D01*
X471278Y-208812D01*
X472778D01*
X467779Y-207312D02*
X468279Y-206812D01*
X469279D01*
X469779Y-207312D01*
Y-207812D01*
X469279Y-208312D01*
X468279D01*
X467779Y-208812D01*
Y-209312D01*
X468279Y-209811D01*
X469279D01*
X469779Y-209312D01*
X464780Y-209811D02*
X466780D01*
X464780Y-207812D01*
Y-207312D01*
X465280Y-206812D01*
X466280D01*
X466780Y-207312D01*
X459782Y-209811D02*
X460782Y-208812D01*
Y-207812D01*
X459782Y-206812D01*
X458283D02*
Y-209811D01*
X456783D01*
X456283Y-209312D01*
Y-207312D01*
X456783Y-206812D01*
X458283D01*
X453784Y-209811D02*
X454784D01*
X455283Y-209312D01*
Y-208312D01*
X454784Y-207812D01*
X453784D01*
X453284Y-208312D01*
Y-208812D01*
X455283D01*
X452284Y-206812D02*
Y-209811D01*
X450785D01*
X450285Y-209312D01*
Y-208812D01*
Y-208312D01*
X450785Y-207812D01*
X452284D01*
X449285D02*
Y-209312D01*
X448785Y-209811D01*
X447286D01*
Y-207812D01*
X445287Y-210811D02*
X444787D01*
X444287Y-210311D01*
Y-207812D01*
X445787D01*
X446286Y-208312D01*
Y-209312D01*
X445787Y-209811D01*
X444287D01*
X443287D02*
X441288Y-207812D01*
X440288Y-209811D02*
Y-206812D01*
X438789D01*
X438289Y-207312D01*
Y-208312D01*
X438789Y-208812D01*
X440288D01*
X437289Y-207812D02*
Y-209811D01*
Y-208812D01*
X436789Y-208312D01*
X436290Y-207812D01*
X435790D01*
X433790Y-209811D02*
X432791D01*
X432291Y-209312D01*
Y-208312D01*
X432791Y-207812D01*
X433790D01*
X434290Y-208312D01*
Y-209312D01*
X433790Y-209811D01*
X430292Y-210811D02*
X429792D01*
X429292Y-210311D01*
Y-207812D01*
X430791D01*
X431291Y-208312D01*
Y-209312D01*
X430791Y-209811D01*
X429292D01*
X428292D02*
X427292Y-208812D01*
Y-207812D01*
X428292Y-206812D01*
X562957Y-237834D02*
Y-240833D01*
X560957D01*
X557958Y-237834D02*
X559958D01*
Y-240833D01*
X557958D01*
X559958Y-239333D02*
X558958D01*
X556959Y-237834D02*
Y-240833D01*
X555459D01*
X554959Y-240333D01*
Y-238334D01*
X555459Y-237834D01*
X556959D01*
X549961Y-240833D02*
X550961Y-239833D01*
Y-238833D01*
X549961Y-237834D01*
X548461D02*
Y-240833D01*
X546962D01*
X546462Y-240333D01*
Y-238334D01*
X546962Y-237834D01*
X548461D01*
X543463Y-240833D02*
X545462D01*
X543463Y-238833D01*
Y-238334D01*
X543963Y-237834D01*
X544963D01*
X545462Y-238334D01*
X540964Y-240833D02*
Y-237834D01*
X542463Y-239333D01*
X540464D01*
X539464Y-240833D02*
X538465Y-239833D01*
Y-238833D01*
X539464Y-237834D01*
X532467D02*
X533466D01*
X533966Y-238334D01*
Y-240333D01*
X533466Y-240833D01*
X532467D01*
X531967Y-240333D01*
Y-238334D01*
X532467Y-237834D01*
X530967Y-240833D02*
Y-238833D01*
X529468D01*
X528968Y-239333D01*
Y-240833D01*
X524469D02*
Y-238334D01*
Y-239333D01*
X524969D01*
X523969D01*
X524469D01*
Y-238334D01*
X523969Y-237834D01*
X521970Y-240833D02*
X520970D01*
X520471Y-240333D01*
Y-239333D01*
X520970Y-238833D01*
X521970D01*
X522470Y-239333D01*
Y-240333D01*
X521970Y-240833D01*
X519471Y-238833D02*
Y-240833D01*
Y-239833D01*
X518971Y-239333D01*
X518471Y-238833D01*
X517971D01*
X513473Y-237834D02*
X512473D01*
X512973D01*
Y-240833D01*
X513473D01*
X512473D01*
X508974D02*
X510974D01*
X508974Y-238833D01*
Y-238334D01*
X509474Y-237834D01*
X510474D01*
X510974Y-238334D01*
X505975D02*
X506475Y-237834D01*
X507475D01*
X507974Y-238334D01*
Y-240333D01*
X507475Y-240833D01*
X506475D01*
X505975Y-240333D01*
X504476Y-241333D02*
X503976Y-240833D01*
Y-240333D01*
X504476D01*
Y-240833D01*
X503976D01*
X504476Y-241333D01*
X504976Y-241832D01*
X497478Y-237834D02*
X498478D01*
X498977Y-238334D01*
Y-240333D01*
X498478Y-240833D01*
X497478D01*
X496978Y-240333D01*
Y-238334D01*
X497478Y-237834D01*
X495479Y-240833D02*
Y-238334D01*
Y-239333D01*
X495978D01*
X494979D01*
X495479D01*
Y-238334D01*
X494979Y-237834D01*
X492979Y-240833D02*
Y-238334D01*
Y-239333D01*
X493479D01*
X492480D01*
X492979D01*
Y-238334D01*
X492480Y-237834D01*
X487481Y-240833D02*
Y-238334D01*
Y-239333D01*
X487981D01*
X486981D01*
X487481D01*
Y-238334D01*
X486981Y-237834D01*
X484982Y-240833D02*
X483982D01*
X483483Y-240333D01*
Y-239333D01*
X483982Y-238833D01*
X484982D01*
X485482Y-239333D01*
Y-240333D01*
X484982Y-240833D01*
X482483Y-238833D02*
Y-240833D01*
Y-239833D01*
X481983Y-239333D01*
X481483Y-238833D01*
X480983D01*
X476485Y-237834D02*
Y-240333D01*
X475985Y-240833D01*
X474985D01*
X474485Y-240333D01*
Y-237834D01*
X473486Y-240833D02*
Y-238833D01*
X472486Y-237834D01*
X471486Y-238833D01*
Y-240833D01*
Y-239333D01*
X473486D01*
X470487Y-240833D02*
Y-237834D01*
X468987D01*
X468487Y-238334D01*
Y-239333D01*
X468987Y-239833D01*
X470487D01*
X469487D02*
X468487Y-240833D01*
X467488Y-237834D02*
X465488D01*
X466488D01*
Y-240833D01*
X564136Y-170921D02*
Y-173919D01*
X562137D01*
X559138Y-170921D02*
X561137D01*
Y-173919D01*
X559138D01*
X561137Y-172420D02*
X560137D01*
X558138Y-170921D02*
Y-173919D01*
X556638D01*
X556139Y-173420D01*
Y-171420D01*
X556638Y-170921D01*
X558138D01*
X551140Y-173919D02*
X552140Y-172920D01*
Y-171920D01*
X551140Y-170921D01*
X549641D02*
Y-173919D01*
X548141D01*
X547641Y-173420D01*
Y-171420D01*
X548141Y-170921D01*
X549641D01*
X546642Y-173919D02*
X545642D01*
X546142D01*
Y-170921D01*
X546642Y-171420D01*
X544142Y-173420D02*
X543643Y-173919D01*
X542643D01*
X542143Y-173420D01*
Y-171420D01*
X542643Y-170921D01*
X543643D01*
X544142Y-171420D01*
Y-171920D01*
X543643Y-172420D01*
X542143D01*
X541143Y-173919D02*
X540144Y-172920D01*
Y-171920D01*
X541143Y-170921D01*
X534146D02*
X535145D01*
X535645Y-171420D01*
Y-173420D01*
X535145Y-173919D01*
X534146D01*
X533646Y-173420D01*
Y-171420D01*
X534146Y-170921D01*
X532646Y-173919D02*
Y-171920D01*
X531147D01*
X530647Y-172420D01*
Y-173919D01*
X526148D02*
Y-171420D01*
Y-172420D01*
X526648D01*
X525648D01*
X526148D01*
Y-171420D01*
X525648Y-170921D01*
X523649Y-173919D02*
X522649D01*
X522150Y-173420D01*
Y-172420D01*
X522649Y-171920D01*
X523649D01*
X524149Y-172420D01*
Y-173420D01*
X523649Y-173919D01*
X521150Y-171920D02*
Y-173919D01*
Y-172920D01*
X520650Y-172420D01*
X520150Y-171920D01*
X519650D01*
X515152Y-173919D02*
Y-170921D01*
X513652D01*
X513153Y-171420D01*
Y-172420D01*
X513652Y-172920D01*
X515152D01*
X514152D02*
X513153Y-173919D01*
X510153Y-171420D02*
X510653Y-170921D01*
X511653D01*
X512153Y-171420D01*
Y-173420D01*
X511653Y-173919D01*
X510653D01*
X510153Y-173420D01*
X509154Y-170921D02*
Y-173919D01*
X507654D01*
X507154Y-173420D01*
Y-172920D01*
X507654Y-172420D01*
X509154D01*
X507654D01*
X507154Y-171920D01*
Y-171420D01*
X507654Y-170921D01*
X509154D01*
X505655Y-174419D02*
X505155Y-173919D01*
Y-173420D01*
X505655D01*
Y-173919D01*
X505155D01*
X505655Y-174419D01*
X506155Y-174919D01*
X498657Y-170921D02*
X499657D01*
X500157Y-171420D01*
Y-173420D01*
X499657Y-173919D01*
X498657D01*
X498157Y-173420D01*
Y-171420D01*
X498657Y-170921D01*
X496658Y-173919D02*
Y-171420D01*
Y-172420D01*
X497158D01*
X496158D01*
X496658D01*
Y-171420D01*
X496158Y-170921D01*
X494159Y-173919D02*
Y-171420D01*
Y-172420D01*
X494658D01*
X493659D01*
X494159D01*
Y-171420D01*
X493659Y-170921D01*
X488660Y-173919D02*
Y-171420D01*
Y-172420D01*
X489160D01*
X488161D01*
X488660D01*
Y-171420D01*
X488161Y-170921D01*
X486161Y-173919D02*
X485161D01*
X484662Y-173420D01*
Y-172420D01*
X485161Y-171920D01*
X486161D01*
X486661Y-172420D01*
Y-173420D01*
X486161Y-173919D01*
X483662Y-171920D02*
Y-173919D01*
Y-172920D01*
X483162Y-172420D01*
X482662Y-171920D01*
X482163D01*
X477664Y-173919D02*
Y-170921D01*
X476664Y-171920D01*
X475665Y-170921D01*
Y-173919D01*
X472666D02*
X474665D01*
X472666Y-171920D01*
Y-171420D01*
X473165Y-170921D01*
X474165D01*
X474665Y-171420D01*
X548969Y-201513D02*
X550969D01*
Y-203012D01*
X549969D01*
X550969D01*
Y-204512D01*
X547969D02*
Y-201513D01*
X546470D01*
X545970Y-202013D01*
Y-203012D01*
X546470Y-203512D01*
X547969D01*
X542971Y-202013D02*
X543471Y-201513D01*
X544471D01*
X544970Y-202013D01*
Y-204012D01*
X544471Y-204512D01*
X543471D01*
X542971Y-204012D01*
Y-203012D01*
X543971D01*
X541971Y-204512D02*
Y-202513D01*
X540972Y-201513D01*
X539972Y-202513D01*
Y-204512D01*
Y-203012D01*
X541971D01*
X534474Y-204512D02*
X535973Y-203012D01*
X534474Y-201513D01*
X532974Y-203012D02*
X530975D01*
X529975Y-204512D02*
X528476Y-203012D01*
X529975Y-201513D01*
X522478Y-202013D02*
X522978Y-201513D01*
X523977D01*
X524477Y-202013D01*
Y-204012D01*
X523977Y-204512D01*
X522978D01*
X522478Y-204012D01*
Y-203012D01*
X523477D01*
X521478Y-204512D02*
Y-201513D01*
X519979D01*
X519479Y-202013D01*
Y-203012D01*
X519979Y-203512D01*
X521478D01*
X516480Y-202013D02*
X516980Y-201513D01*
X517979D01*
X518479Y-202013D01*
Y-202513D01*
X517979Y-203012D01*
X516980D01*
X516480Y-203512D01*
Y-204012D01*
X516980Y-204512D01*
X517979D01*
X518479Y-204012D01*
X513481Y-204512D02*
X515480D01*
X513481Y-202513D01*
Y-202013D01*
X513980Y-201513D01*
X514980D01*
X515480Y-202013D01*
X508482Y-204512D02*
X509482Y-203512D01*
Y-202513D01*
X508482Y-201513D01*
X506983Y-204512D02*
Y-201513D01*
X504983Y-204512D01*
Y-201513D01*
X503484Y-204512D02*
X502484D01*
X501984Y-204012D01*
Y-203012D01*
X502484Y-202513D01*
X503484D01*
X503984Y-203012D01*
Y-204012D01*
X503484Y-204512D01*
X500985Y-202513D02*
Y-204512D01*
Y-203512D01*
X500485Y-203012D01*
X499985Y-202513D01*
X499485D01*
X497986Y-204512D02*
Y-202513D01*
X497486D01*
X496986Y-203012D01*
Y-204512D01*
Y-203012D01*
X496486Y-202513D01*
X495986Y-203012D01*
Y-204512D01*
X494487Y-202513D02*
X493487D01*
X492987Y-203012D01*
Y-204512D01*
X494487D01*
X494987Y-204012D01*
X494487Y-203512D01*
X492987D01*
X491988Y-204512D02*
X490988D01*
X491488D01*
Y-201513D01*
X491988D01*
X489488Y-204512D02*
X488489Y-203512D01*
Y-202513D01*
X489488Y-201513D01*
X565198Y-181222D02*
Y-184221D01*
X563199D01*
X560200Y-181222D02*
X562199D01*
Y-184221D01*
X560200D01*
X562199Y-182721D02*
X561199D01*
X559200Y-181222D02*
Y-184221D01*
X557701D01*
X557201Y-183721D01*
Y-181722D01*
X557701Y-181222D01*
X559200D01*
X552202Y-184221D02*
X553202Y-183221D01*
Y-182222D01*
X552202Y-181222D01*
X550703D02*
Y-184221D01*
X549203D01*
X548703Y-183721D01*
Y-181722D01*
X549203Y-181222D01*
X550703D01*
X547704Y-184221D02*
X546704D01*
X547204D01*
Y-181222D01*
X547704Y-181722D01*
X543205Y-184221D02*
X545205D01*
X543205Y-182222D01*
Y-181722D01*
X543705Y-181222D01*
X544705D01*
X545205Y-181722D01*
X542206Y-184221D02*
X541206Y-183221D01*
Y-182222D01*
X542206Y-181222D01*
X535208D02*
X536207D01*
X536707Y-181722D01*
Y-183721D01*
X536207Y-184221D01*
X535208D01*
X534708Y-183721D01*
Y-181722D01*
X535208Y-181222D01*
X533708Y-184221D02*
Y-182222D01*
X532209D01*
X531709Y-182721D01*
Y-184221D01*
X527210D02*
Y-181722D01*
Y-182721D01*
X527710D01*
X526711D01*
X527210D01*
Y-181722D01*
X526711Y-181222D01*
X524711Y-184221D02*
X523712D01*
X523212Y-183721D01*
Y-182721D01*
X523712Y-182222D01*
X524711D01*
X525211Y-182721D01*
Y-183721D01*
X524711Y-184221D01*
X522212Y-182222D02*
Y-184221D01*
Y-183221D01*
X521712Y-182721D01*
X521212Y-182222D01*
X520713D01*
X516214Y-184221D02*
Y-181222D01*
X514714D01*
X514215Y-181722D01*
Y-182721D01*
X514714Y-183221D01*
X516214D01*
X515214D02*
X514215Y-184221D01*
X511216Y-181722D02*
X511715Y-181222D01*
X512715D01*
X513215Y-181722D01*
Y-183721D01*
X512715Y-184221D01*
X511715D01*
X511216Y-183721D01*
X510216Y-181222D02*
Y-184221D01*
X508716D01*
X508217Y-183721D01*
Y-183221D01*
X508716Y-182721D01*
X510216D01*
X508716D01*
X508217Y-182222D01*
Y-181722D01*
X508716Y-181222D01*
X510216D01*
X506717Y-184721D02*
X506217Y-184221D01*
Y-183721D01*
X506717D01*
Y-184221D01*
X506217D01*
X506717Y-184721D01*
X507217Y-185221D01*
X499719Y-181222D02*
X500719D01*
X501219Y-181722D01*
Y-183721D01*
X500719Y-184221D01*
X499719D01*
X499220Y-183721D01*
Y-181722D01*
X499719Y-181222D01*
X497720Y-184221D02*
Y-181722D01*
Y-182721D01*
X498220D01*
X497220D01*
X497720D01*
Y-181722D01*
X497220Y-181222D01*
X495221Y-184221D02*
Y-181722D01*
Y-182721D01*
X495721D01*
X494721D01*
X495221D01*
Y-181722D01*
X494721Y-181222D01*
X489723Y-184221D02*
Y-181722D01*
Y-182721D01*
X490222D01*
X489223D01*
X489723D01*
Y-181722D01*
X489223Y-181222D01*
X487223Y-184221D02*
X486224D01*
X485724Y-183721D01*
Y-182721D01*
X486224Y-182222D01*
X487223D01*
X487723Y-182721D01*
Y-183721D01*
X487223Y-184221D01*
X484724Y-182222D02*
Y-184221D01*
Y-183221D01*
X484224Y-182721D01*
X483724Y-182222D01*
X483225D01*
X478726Y-184221D02*
Y-181222D01*
X477727Y-182222D01*
X476727Y-181222D01*
Y-184221D01*
X473728D02*
X475727D01*
X473728Y-182222D01*
Y-181722D01*
X474228Y-181222D01*
X475227D01*
X475727Y-181722D01*
X595725Y-272123D02*
Y-274622D01*
X595225Y-275122D01*
X594225D01*
X593725Y-274622D01*
Y-272123D01*
X592726Y-272622D02*
X592226Y-272123D01*
X591226D01*
X590726Y-272622D01*
Y-273122D01*
X591226Y-273622D01*
X591726D01*
X591226D01*
X590726Y-274122D01*
Y-274622D01*
X591226Y-275122D01*
X592226D01*
X592726Y-274622D01*
X589727Y-272622D02*
X589227Y-272123D01*
X588227D01*
X587727Y-272622D01*
Y-273122D01*
X588227Y-273622D01*
X588727D01*
X588227D01*
X587727Y-274122D01*
Y-274622D01*
X588227Y-275122D01*
X589227D01*
X589727Y-274622D01*
X560662Y-270791D02*
Y-267792D01*
X559162D01*
X558663Y-268292D01*
Y-269291D01*
X559162Y-269791D01*
X560662D01*
X559662D02*
X558663Y-270791D01*
X557663D02*
X556663D01*
X557163D01*
Y-267792D01*
X557663Y-268292D01*
X555164D02*
X554664Y-267792D01*
X553664D01*
X553164Y-268292D01*
Y-268792D01*
X553664Y-269291D01*
X553164Y-269791D01*
Y-270291D01*
X553664Y-270791D01*
X554664D01*
X555164Y-270291D01*
Y-269791D01*
X554664Y-269291D01*
X555164Y-268792D01*
Y-268292D01*
X554664Y-269291D02*
X553664D01*
X550165Y-270791D02*
X552165D01*
X550165Y-268792D01*
Y-268292D01*
X550665Y-267792D01*
X551665D01*
X552165Y-268292D01*
X544170Y-284779D02*
X547169D01*
Y-283279D01*
X546669Y-282780D01*
X545669D01*
X545169Y-283279D01*
Y-284779D01*
Y-283779D02*
X544170Y-282780D01*
Y-281780D02*
Y-280780D01*
Y-281280D01*
X547169D01*
X546669Y-281780D01*
Y-279281D02*
X547169Y-278781D01*
Y-277781D01*
X546669Y-277281D01*
X546169D01*
X545669Y-277781D01*
X545169Y-277281D01*
X544670D01*
X544170Y-277781D01*
Y-278781D01*
X544670Y-279281D01*
X545169D01*
X545669Y-278781D01*
X546169Y-279281D01*
X546669D01*
X545669Y-278781D02*
Y-277781D01*
X544170Y-276282D02*
Y-275282D01*
Y-275782D01*
X547169D01*
X546669Y-276282D01*
X572965Y-270004D02*
Y-267004D01*
X571465D01*
X570965Y-267504D01*
Y-268504D01*
X571465Y-269004D01*
X572965D01*
X571965D02*
X570965Y-270004D01*
X569966D02*
X568966D01*
X569466D01*
Y-267004D01*
X569966Y-267504D01*
X567467D02*
X566967Y-267004D01*
X565967D01*
X565467Y-267504D01*
Y-268004D01*
X565967Y-268504D01*
X565467Y-269004D01*
Y-269504D01*
X565967Y-270004D01*
X566967D01*
X567467Y-269504D01*
Y-269004D01*
X566967Y-268504D01*
X567467Y-268004D01*
Y-267504D01*
X566967Y-268504D02*
X565967D01*
X564468Y-267504D02*
X563968Y-267004D01*
X562968D01*
X562468Y-267504D01*
Y-269504D01*
X562968Y-270004D01*
X563968D01*
X564468Y-269504D01*
Y-267504D01*
X529958Y-285213D02*
Y-288212D01*
X531457D01*
X531957Y-287712D01*
Y-286712D01*
X531457Y-286212D01*
X529958D01*
X530957D02*
X531957Y-285213D01*
X534456D02*
Y-288212D01*
X532957Y-286712D01*
X534956D01*
X535956Y-285713D02*
X536455Y-285213D01*
X537455D01*
X537955Y-285713D01*
Y-287712D01*
X537455Y-288212D01*
X536455D01*
X535956Y-287712D01*
Y-287212D01*
X536455Y-286712D01*
X537955D01*
X598607Y-265111D02*
X598107Y-264611D01*
Y-263612D01*
X598607Y-263112D01*
X600606D01*
X601106Y-263612D01*
Y-264611D01*
X600606Y-265111D01*
X601106Y-266111D02*
Y-267111D01*
Y-266611D01*
X598107D01*
X598607Y-266111D01*
X601106Y-268610D02*
Y-269610D01*
Y-269110D01*
X598107D01*
X598607Y-268610D01*
X598107Y-273109D02*
Y-271109D01*
X599606D01*
X599107Y-272109D01*
Y-272609D01*
X599606Y-273109D01*
X600606D01*
X601106Y-272609D01*
Y-271609D01*
X600606Y-271109D01*
X603362Y-289219D02*
X603862Y-289719D01*
Y-290719D01*
X603362Y-291219D01*
X601363D01*
X600863Y-290719D01*
Y-289719D01*
X601363Y-289219D01*
X600863Y-288220D02*
Y-287220D01*
Y-287720D01*
X603862D01*
X603362Y-288220D01*
X600863Y-285721D02*
Y-284721D01*
Y-285221D01*
X603862D01*
X603362Y-285721D01*
X600863Y-281722D02*
X603862D01*
X602362Y-283221D01*
Y-281222D01*
X554088Y-287614D02*
X553588Y-288114D01*
X552588D01*
X552088Y-287614D01*
Y-285614D01*
X552588Y-285115D01*
X553588D01*
X554088Y-285614D01*
X555087Y-285115D02*
X556087D01*
X555587D01*
Y-288114D01*
X555087Y-287614D01*
X557586Y-285115D02*
X558586D01*
X558086D01*
Y-288114D01*
X557586Y-287614D01*
X560086D02*
X560585Y-288114D01*
X561585D01*
X562085Y-287614D01*
Y-287114D01*
X561585Y-286614D01*
X561085D01*
X561585D01*
X562085Y-286114D01*
Y-285614D01*
X561585Y-285115D01*
X560585D01*
X560086Y-285614D01*
X580496Y-265505D02*
X579996Y-265005D01*
Y-264005D01*
X580496Y-263506D01*
X582496D01*
X582996Y-264005D01*
Y-265005D01*
X582496Y-265505D01*
X582996Y-266505D02*
Y-267504D01*
Y-267004D01*
X579996D01*
X580496Y-266505D01*
X582996Y-269004D02*
Y-270004D01*
Y-269504D01*
X579996D01*
X580496Y-269004D01*
X582996Y-273502D02*
Y-271503D01*
X580996Y-273502D01*
X580496D01*
X579996Y-273003D01*
Y-272003D01*
X580496Y-271503D01*
X582496Y-297775D02*
X582996Y-298275D01*
Y-299274D01*
X582496Y-299774D01*
X580496D01*
X579997Y-299274D01*
Y-298275D01*
X580496Y-297775D01*
X579997Y-296775D02*
Y-295775D01*
Y-296275D01*
X582996D01*
X582496Y-296775D01*
X579997Y-294276D02*
Y-293276D01*
Y-293776D01*
X582996D01*
X582496Y-294276D01*
X579997Y-291777D02*
Y-290777D01*
Y-291277D01*
X582996D01*
X582496Y-291777D01*
X543882Y-259993D02*
X543382Y-259493D01*
Y-258494D01*
X543882Y-257994D01*
X545882D01*
X546381Y-258494D01*
Y-259493D01*
X545882Y-259993D01*
X546381Y-260993D02*
Y-261993D01*
Y-261493D01*
X543382D01*
X543882Y-260993D01*
X546381Y-263492D02*
Y-264492D01*
Y-263992D01*
X543382D01*
X543882Y-263492D01*
Y-265991D02*
X543382Y-266491D01*
Y-267491D01*
X543882Y-267990D01*
X545882D01*
X546381Y-267491D01*
Y-266491D01*
X545882Y-265991D01*
X543882D01*
D19*
X290551Y-275590D02*
Y-271654D01*
D24*
X597699Y-198350D02*
Y-195351D01*
X596200D01*
X595700Y-195851D01*
Y-196850D01*
X596200Y-197350D01*
X597699D01*
X596700D02*
X595700Y-198350D01*
X594700Y-195851D02*
X594201Y-195351D01*
X593201D01*
X592701Y-195851D01*
Y-196351D01*
X593201Y-196850D01*
X592701Y-197350D01*
Y-197850D01*
X593201Y-198350D01*
X594201D01*
X594700Y-197850D01*
Y-197350D01*
X594201Y-196850D01*
X594700Y-196351D01*
Y-195851D01*
X594201Y-196850D02*
X593201D01*
X591701Y-197850D02*
X591202Y-198350D01*
X590202D01*
X589702Y-197850D01*
Y-195851D01*
X590202Y-195351D01*
X591202D01*
X591701Y-195851D01*
Y-196351D01*
X591202Y-196850D01*
X589702D01*
X579983Y-208586D02*
Y-205587D01*
X578483D01*
X577984Y-206087D01*
Y-207087D01*
X578483Y-207586D01*
X579983D01*
X578983D02*
X577984Y-208586D01*
X576984Y-206087D02*
X576484Y-205587D01*
X575484D01*
X574985Y-206087D01*
Y-206587D01*
X575484Y-207087D01*
X574985Y-207586D01*
Y-208086D01*
X575484Y-208586D01*
X576484D01*
X576984Y-208086D01*
Y-207586D01*
X576484Y-207087D01*
X576984Y-206587D01*
Y-206087D01*
X576484Y-207087D02*
X575484D01*
X573985Y-206087D02*
X573485Y-205587D01*
X572485D01*
X571985Y-206087D01*
Y-206587D01*
X572485Y-207087D01*
X571985Y-207586D01*
Y-208086D01*
X572485Y-208586D01*
X573485D01*
X573985Y-208086D01*
Y-207586D01*
X573485Y-207087D01*
X573985Y-206587D01*
Y-206087D01*
X573485Y-207087D02*
X572485D01*
X274504Y-193276D02*
X274004Y-192776D01*
Y-191777D01*
X274504Y-191277D01*
X276503D01*
X277003Y-191777D01*
Y-192776D01*
X276503Y-193276D01*
Y-194276D02*
X277003Y-194776D01*
Y-195775D01*
X276503Y-196275D01*
X274504D01*
X274004Y-195775D01*
Y-194776D01*
X274504Y-194276D01*
X275003D01*
X275503Y-194776D01*
Y-196275D01*
X274004Y-199274D02*
X274504Y-198275D01*
X275503Y-197275D01*
X276503D01*
X277003Y-197775D01*
Y-198775D01*
X276503Y-199274D01*
X276003D01*
X275503Y-198775D01*
Y-197275D01*
X322472Y-286865D02*
X322972Y-286365D01*
X323971D01*
X324471Y-286865D01*
Y-288864D01*
X323971Y-289364D01*
X322972D01*
X322472Y-288864D01*
X321472D02*
X320972Y-289364D01*
X319973D01*
X319473Y-288864D01*
Y-286865D01*
X319973Y-286365D01*
X320972D01*
X321472Y-286865D01*
Y-287365D01*
X320972Y-287865D01*
X319473D01*
X316474Y-286365D02*
X318473D01*
Y-287865D01*
X317473Y-287365D01*
X316974D01*
X316474Y-287865D01*
Y-288864D01*
X316974Y-289364D01*
X317973D01*
X318473Y-288864D01*
X341369Y-285162D02*
X341869Y-284662D01*
X342869D01*
X343369Y-285162D01*
Y-287161D01*
X342869Y-287661D01*
X341869D01*
X341369Y-287161D01*
X340370D02*
X339870Y-287661D01*
X338870D01*
X338370Y-287161D01*
Y-285162D01*
X338870Y-284662D01*
X339870D01*
X340370Y-285162D01*
Y-285662D01*
X339870Y-286162D01*
X338370D01*
X335871Y-287661D02*
Y-284662D01*
X337371Y-286162D01*
X335371D01*
X610993Y-245488D02*
X610493Y-245988D01*
X609493D01*
X608993Y-245488D01*
Y-243489D01*
X609493Y-242989D01*
X610493D01*
X610993Y-243489D01*
X611993D02*
X612492Y-242989D01*
X613492D01*
X613992Y-243489D01*
Y-245488D01*
X613492Y-245988D01*
X612492D01*
X611993Y-245488D01*
Y-244988D01*
X612492Y-244488D01*
X613992D01*
X614992Y-245488D02*
X615491Y-245988D01*
X616491D01*
X616991Y-245488D01*
Y-244988D01*
X616491Y-244488D01*
X615991D01*
X616491D01*
X616991Y-243988D01*
Y-243489D01*
X616491Y-242989D01*
X615491D01*
X614992Y-243489D01*
X616683Y-223285D02*
X617183Y-222785D01*
X618183D01*
X618682Y-223285D01*
Y-225284D01*
X618183Y-225784D01*
X617183D01*
X616683Y-225284D01*
X615683D02*
X615183Y-225784D01*
X614184D01*
X613684Y-225284D01*
Y-223285D01*
X614184Y-222785D01*
X615183D01*
X615683Y-223285D01*
Y-223784D01*
X615183Y-224284D01*
X613684D01*
X610685Y-225784D02*
X612684D01*
X610685Y-223784D01*
Y-223285D01*
X611185Y-222785D01*
X612184D01*
X612684Y-223285D01*
X616173Y-307662D02*
X616672Y-307162D01*
X617672D01*
X618172Y-307662D01*
Y-309661D01*
X617672Y-310161D01*
X616672D01*
X616173Y-309661D01*
X615173D02*
X614673Y-310161D01*
X613673D01*
X613173Y-309661D01*
Y-307662D01*
X613673Y-307162D01*
X614673D01*
X615173Y-307662D01*
Y-308162D01*
X614673Y-308661D01*
X613173D01*
X612174Y-307662D02*
X611674Y-307162D01*
X610674D01*
X610175Y-307662D01*
Y-309661D01*
X610674Y-310161D01*
X611674D01*
X612174Y-309661D01*
Y-307662D01*
X600363Y-249031D02*
X599863Y-249531D01*
X598863D01*
X598363Y-249031D01*
Y-247032D01*
X598863Y-246532D01*
X599863D01*
X600363Y-247032D01*
X601363Y-249031D02*
X601862Y-249531D01*
X602862D01*
X603362Y-249031D01*
Y-248531D01*
X602862Y-248031D01*
X603362Y-247532D01*
Y-247032D01*
X602862Y-246532D01*
X601862D01*
X601363Y-247032D01*
Y-247532D01*
X601862Y-248031D01*
X601363Y-248531D01*
Y-249031D01*
X601862Y-248031D02*
X602862D01*
X604362Y-249031D02*
X604861Y-249531D01*
X605861D01*
X606361Y-249031D01*
Y-248531D01*
X605861Y-248031D01*
X606361Y-247532D01*
Y-247032D01*
X605861Y-246532D01*
X604861D01*
X604362Y-247032D01*
Y-247532D01*
X604861Y-248031D01*
X604362Y-248531D01*
Y-249031D01*
X604861Y-248031D02*
X605861D01*
X604361Y-234040D02*
X604861Y-233540D01*
X605861D01*
X606361Y-234040D01*
Y-236039D01*
X605861Y-236539D01*
X604861D01*
X604361Y-236039D01*
X603362Y-234040D02*
X602862Y-233540D01*
X601862D01*
X601363Y-234040D01*
Y-234540D01*
X601862Y-235039D01*
X601363Y-235539D01*
Y-236039D01*
X601862Y-236539D01*
X602862D01*
X603362Y-236039D01*
Y-235539D01*
X602862Y-235039D01*
X603362Y-234540D01*
Y-234040D01*
X602862Y-235039D02*
X601862D01*
X600363Y-233540D02*
X598363D01*
Y-234040D01*
X600363Y-236039D01*
Y-236539D01*
X370004Y-151119D02*
X367004D01*
Y-152619D01*
X367504Y-153119D01*
X368504D01*
X369004Y-152619D01*
Y-151119D01*
Y-152119D02*
X370004Y-153119D01*
X367504Y-154118D02*
X367004Y-154618D01*
Y-155618D01*
X367504Y-156118D01*
X368004D01*
X368504Y-155618D01*
X369004Y-156118D01*
X369504D01*
X370004Y-155618D01*
Y-154618D01*
X369504Y-154118D01*
X369004D01*
X368504Y-154618D01*
X368004Y-154118D01*
X367504D01*
X368504Y-154618D02*
Y-155618D01*
X367504Y-157117D02*
X367004Y-157617D01*
Y-158617D01*
X367504Y-159117D01*
X369504D01*
X370004Y-158617D01*
Y-157617D01*
X369504Y-157117D01*
X367504D01*
X380390Y-159511D02*
X383389D01*
Y-158011D01*
X382889Y-157511D01*
X381890D01*
X381390Y-158011D01*
Y-159511D01*
Y-158511D02*
X380390Y-157511D01*
X383389Y-156511D02*
Y-154512D01*
X382889D01*
X380890Y-156511D01*
X380390D01*
X380890Y-153512D02*
X380390Y-153013D01*
Y-152013D01*
X380890Y-151513D01*
X382889D01*
X383389Y-152013D01*
Y-153013D01*
X382889Y-153512D01*
X382390D01*
X381890Y-153013D01*
Y-151513D01*
X579589Y-216066D02*
Y-213067D01*
X578090D01*
X577590Y-213567D01*
Y-214567D01*
X578090Y-215067D01*
X579589D01*
X578590D02*
X577590Y-216066D01*
X576590Y-213067D02*
X574591D01*
Y-213567D01*
X576590Y-215567D01*
Y-216066D01*
X573591Y-213567D02*
X573091Y-213067D01*
X572092D01*
X571592Y-213567D01*
Y-214067D01*
X572092Y-214567D01*
X571592Y-215067D01*
Y-215567D01*
X572092Y-216066D01*
X573091D01*
X573591Y-215567D01*
Y-215067D01*
X573091Y-214567D01*
X573591Y-214067D01*
Y-213567D01*
X573091Y-214567D02*
X572092D01*
X411873Y-106224D02*
Y-103225D01*
X410373D01*
X409873Y-103725D01*
Y-104724D01*
X410373Y-105224D01*
X411873D01*
X410873D02*
X409873Y-106224D01*
X408874Y-103225D02*
X406874D01*
Y-103725D01*
X408874Y-105724D01*
Y-106224D01*
X405875Y-103725D02*
X405375Y-103225D01*
X404375D01*
X403875Y-103725D01*
Y-105724D01*
X404375Y-106224D01*
X405375D01*
X405875Y-105724D01*
Y-103725D01*
X403211Y-126696D02*
Y-123697D01*
X401712D01*
X401212Y-124197D01*
Y-125197D01*
X401712Y-125697D01*
X403211D01*
X402212D02*
X401212Y-126696D01*
X398213Y-123697D02*
X399213Y-124197D01*
X400212Y-125197D01*
Y-126197D01*
X399712Y-126696D01*
X398713D01*
X398213Y-126197D01*
Y-125697D01*
X398713Y-125197D01*
X400212D01*
X397213Y-124197D02*
X396713Y-123697D01*
X395714D01*
X395214Y-124197D01*
Y-124697D01*
X395714Y-125197D01*
X395214Y-125697D01*
Y-126197D01*
X395714Y-126696D01*
X396713D01*
X397213Y-126197D01*
Y-125697D01*
X396713Y-125197D01*
X397213Y-124697D01*
Y-124197D01*
X396713Y-125197D02*
X395714D01*
X413841Y-137326D02*
Y-134327D01*
X412342D01*
X411842Y-134827D01*
Y-135827D01*
X412342Y-136327D01*
X413841D01*
X412842D02*
X411842Y-137326D01*
X408843Y-134327D02*
X409842Y-134827D01*
X410842Y-135827D01*
Y-136826D01*
X410342Y-137326D01*
X409343D01*
X408843Y-136826D01*
Y-136327D01*
X409343Y-135827D01*
X410842D01*
X407843Y-134327D02*
X405844D01*
Y-134827D01*
X407843Y-136826D01*
Y-137326D01*
X48093Y-40870D02*
Y-37871D01*
X46594D01*
X46094Y-38370D01*
Y-39370D01*
X46594Y-39870D01*
X48093D01*
X47093D02*
X46094Y-40870D01*
X43095Y-37871D02*
X44094Y-38370D01*
X45094Y-39370D01*
Y-40370D01*
X44594Y-40870D01*
X43595D01*
X43095Y-40370D01*
Y-39870D01*
X43595Y-39370D01*
X45094D01*
X40096Y-37871D02*
X41095Y-38370D01*
X42095Y-39370D01*
Y-40370D01*
X41595Y-40870D01*
X40596D01*
X40096Y-40370D01*
Y-39870D01*
X40596Y-39370D01*
X42095D01*
X48487Y-53468D02*
Y-50469D01*
X46987D01*
X46488Y-50969D01*
Y-51968D01*
X46987Y-52468D01*
X48487D01*
X47487D02*
X46488Y-53468D01*
X43488Y-50469D02*
X44488Y-50969D01*
X45488Y-51968D01*
Y-52968D01*
X44988Y-53468D01*
X43988D01*
X43488Y-52968D01*
Y-52468D01*
X43988Y-51968D01*
X45488D01*
X40490Y-50469D02*
X42489D01*
Y-51968D01*
X41489Y-51469D01*
X40989D01*
X40490Y-51968D01*
Y-52968D01*
X40989Y-53468D01*
X41989D01*
X42489Y-52968D01*
X601650Y-85495D02*
X604649D01*
Y-83995D01*
X604149Y-83495D01*
X603150D01*
X602650Y-83995D01*
Y-85495D01*
Y-84495D02*
X601650Y-83495D01*
X604649Y-80496D02*
X604149Y-81496D01*
X603150Y-82496D01*
X602150D01*
X601650Y-81996D01*
Y-80996D01*
X602150Y-80496D01*
X602650D01*
X603150Y-80996D01*
Y-82496D01*
X601650Y-77997D02*
X604649D01*
X603150Y-79497D01*
Y-77497D01*
X433920Y-127877D02*
Y-124878D01*
X432420D01*
X431921Y-125378D01*
Y-126378D01*
X432420Y-126878D01*
X433920D01*
X432920D02*
X431921Y-127877D01*
X428922Y-124878D02*
X429921Y-125378D01*
X430921Y-126378D01*
Y-127378D01*
X430421Y-127877D01*
X429421D01*
X428922Y-127378D01*
Y-126878D01*
X429421Y-126378D01*
X430921D01*
X427922Y-125378D02*
X427422Y-124878D01*
X426422D01*
X425922Y-125378D01*
Y-125878D01*
X426422Y-126378D01*
X426922D01*
X426422D01*
X425922Y-126878D01*
Y-127378D01*
X426422Y-127877D01*
X427422D01*
X427922Y-127378D01*
X598557Y-76647D02*
X595558D01*
Y-78146D01*
X596058Y-78646D01*
X597057D01*
X597557Y-78146D01*
Y-76647D01*
Y-77647D02*
X598557Y-78646D01*
X595558Y-81645D02*
X596058Y-80646D01*
X597057Y-79646D01*
X598057D01*
X598557Y-80146D01*
Y-81146D01*
X598057Y-81645D01*
X597557D01*
X597057Y-81146D01*
Y-79646D01*
X598557Y-84644D02*
Y-82645D01*
X596557Y-84644D01*
X596058D01*
X595558Y-84145D01*
Y-83145D01*
X596058Y-82645D01*
X429089Y-143232D02*
Y-140233D01*
X427590D01*
X427090Y-140733D01*
Y-141732D01*
X427590Y-142232D01*
X429089D01*
X428090D02*
X427090Y-143232D01*
X424091Y-140233D02*
X425091Y-140733D01*
X426090Y-141732D01*
Y-142732D01*
X425591Y-143232D01*
X424591D01*
X424091Y-142732D01*
Y-142232D01*
X424591Y-141732D01*
X426090D01*
X423091Y-143232D02*
X422092D01*
X422591D01*
Y-140233D01*
X423091Y-140733D01*
X48167Y-2634D02*
Y-5633D01*
X49666D01*
X50166Y-5133D01*
Y-4134D01*
X49666Y-3634D01*
X48167D01*
X49166D02*
X50166Y-2634D01*
X53165Y-5633D02*
X52165Y-5133D01*
X51166Y-4134D01*
Y-3134D01*
X51666Y-2634D01*
X52665D01*
X53165Y-3134D01*
Y-3634D01*
X52665Y-4134D01*
X51166D01*
X54165Y-5133D02*
X54664Y-5633D01*
X55664D01*
X56164Y-5133D01*
Y-3134D01*
X55664Y-2634D01*
X54664D01*
X54165Y-3134D01*
Y-5133D01*
X73881Y3815D02*
Y6814D01*
X72381D01*
X71881Y6315D01*
Y5315D01*
X72381Y4815D01*
X73881D01*
X72881D02*
X71881Y3815D01*
X68882Y6814D02*
X70882D01*
Y5315D01*
X69882Y5815D01*
X69382D01*
X68882Y5315D01*
Y4315D01*
X69382Y3815D01*
X70382D01*
X70882Y4315D01*
X67883D02*
X67383Y3815D01*
X66383D01*
X65883Y4315D01*
Y6315D01*
X66383Y6814D01*
X67383D01*
X67883Y6315D01*
Y5815D01*
X67383Y5315D01*
X65883D01*
X387432Y-127741D02*
X387932Y-127241D01*
X388932D01*
X389432Y-127741D01*
Y-129740D01*
X388932Y-130240D01*
X387932D01*
X387432Y-129740D01*
X386433Y-127741D02*
X385933Y-127241D01*
X384933D01*
X384433Y-127741D01*
Y-128240D01*
X384933Y-128740D01*
X384433Y-129240D01*
Y-129740D01*
X384933Y-130240D01*
X385933D01*
X386433Y-129740D01*
Y-129240D01*
X385933Y-128740D01*
X386433Y-128240D01*
Y-127741D01*
X385933Y-128740D02*
X384933D01*
X381434Y-127241D02*
X383434D01*
Y-128740D01*
X382434Y-128240D01*
X381934D01*
X381434Y-128740D01*
Y-129740D01*
X381934Y-130240D01*
X382934D01*
X383434Y-129740D01*
X178270Y-125067D02*
X178769Y-125567D01*
Y-126567D01*
X178270Y-127066D01*
X176270D01*
X175770Y-126567D01*
Y-125567D01*
X176270Y-125067D01*
X178270Y-124067D02*
X178769Y-123567D01*
Y-122568D01*
X178270Y-122068D01*
X177770D01*
X177270Y-122568D01*
X176770Y-122068D01*
X176270D01*
X175770Y-122568D01*
Y-123567D01*
X176270Y-124067D01*
X176770D01*
X177270Y-123567D01*
X177770Y-124067D01*
X178270D01*
X177270Y-123567D02*
Y-122568D01*
X175770Y-119569D02*
X178769D01*
X177270Y-121068D01*
Y-119069D01*
X379558Y-238370D02*
X380058Y-237871D01*
X381058D01*
X381558Y-238370D01*
Y-240370D01*
X381058Y-240870D01*
X380058D01*
X379558Y-240370D01*
X378559Y-237871D02*
X376559D01*
Y-238370D01*
X378559Y-240370D01*
Y-240870D01*
X375560Y-238370D02*
X375060Y-237871D01*
X374060D01*
X373560Y-238370D01*
Y-240370D01*
X374060Y-240870D01*
X375060D01*
X375560Y-240370D01*
Y-238370D01*
X327590Y-232465D02*
X328090Y-231965D01*
X329089D01*
X329589Y-232465D01*
Y-234464D01*
X329089Y-234964D01*
X328090D01*
X327590Y-234464D01*
X324591Y-231965D02*
X325590Y-232465D01*
X326590Y-233465D01*
Y-234464D01*
X326090Y-234964D01*
X325091D01*
X324591Y-234464D01*
Y-233964D01*
X325091Y-233465D01*
X326590D01*
X323591Y-234464D02*
X323091Y-234964D01*
X322092D01*
X321592Y-234464D01*
Y-232465D01*
X322092Y-231965D01*
X323091D01*
X323591Y-232465D01*
Y-232965D01*
X323091Y-233465D01*
X321592D01*
X153482Y-145745D02*
Y-148744D01*
X154981D01*
X155481Y-148244D01*
Y-147244D01*
X154981Y-146744D01*
X153482D01*
X154481D02*
X155481Y-145745D01*
X158480Y-148744D02*
X156481D01*
Y-147244D01*
X157480Y-147744D01*
X157980D01*
X158480Y-147244D01*
Y-146244D01*
X157980Y-145745D01*
X156981D01*
X156481Y-146244D01*
X159480Y-148244D02*
X159979Y-148744D01*
X160979D01*
X161479Y-148244D01*
Y-147744D01*
X160979Y-147244D01*
X161479Y-146744D01*
Y-146244D01*
X160979Y-145745D01*
X159979D01*
X159480Y-146244D01*
Y-146744D01*
X159979Y-147244D01*
X159480Y-147744D01*
Y-148244D01*
X159979Y-147244D02*
X160979D01*
X177877Y-93245D02*
X174878D01*
Y-94745D01*
X175378Y-95245D01*
X176378D01*
X176878Y-94745D01*
Y-93245D01*
Y-94245D02*
X177877Y-95245D01*
X174878Y-98244D02*
Y-96244D01*
X176378D01*
X175878Y-97244D01*
Y-97744D01*
X176378Y-98244D01*
X177378D01*
X177877Y-97744D01*
Y-96744D01*
X177378Y-96244D01*
X174878Y-99243D02*
Y-101243D01*
X175378D01*
X177378Y-99243D01*
X177877D01*
X153088Y-165036D02*
Y-168035D01*
X154587D01*
X155087Y-167535D01*
Y-166535D01*
X154587Y-166036D01*
X153088D01*
X154088D02*
X155087Y-165036D01*
X158086Y-168035D02*
X156087D01*
Y-166535D01*
X157087Y-167035D01*
X157587D01*
X158086Y-166535D01*
Y-165536D01*
X157587Y-165036D01*
X156587D01*
X156087Y-165536D01*
X161085Y-168035D02*
X160086Y-167535D01*
X159086Y-166535D01*
Y-165536D01*
X159586Y-165036D01*
X160585D01*
X161085Y-165536D01*
Y-166036D01*
X160585Y-166535D01*
X159086D01*
X153482Y-150469D02*
Y-153468D01*
X154981D01*
X155481Y-152968D01*
Y-151969D01*
X154981Y-151469D01*
X153482D01*
X154481D02*
X155481Y-150469D01*
X158480Y-153468D02*
X156481D01*
Y-151969D01*
X157480Y-152468D01*
X157980D01*
X158480Y-151969D01*
Y-150969D01*
X157980Y-150469D01*
X156981D01*
X156481Y-150969D01*
X161479Y-153468D02*
X159480D01*
Y-151969D01*
X160479Y-152468D01*
X160979D01*
X161479Y-151969D01*
Y-150969D01*
X160979Y-150469D01*
X159979D01*
X159480Y-150969D01*
X153482Y-155587D02*
Y-158586D01*
X154981D01*
X155481Y-158086D01*
Y-157087D01*
X154981Y-156587D01*
X153482D01*
X154481D02*
X155481Y-155587D01*
X158480Y-158586D02*
X156481D01*
Y-157087D01*
X157480Y-157586D01*
X157980D01*
X158480Y-157087D01*
Y-156087D01*
X157980Y-155587D01*
X156981D01*
X156481Y-156087D01*
X160979Y-155587D02*
Y-158586D01*
X159480Y-157087D01*
X161479D01*
X162537Y-139445D02*
Y-142444D01*
X164036D01*
X164536Y-141945D01*
Y-140945D01*
X164036Y-140445D01*
X162537D01*
X163536D02*
X164536Y-139445D01*
X167535Y-142444D02*
X165536D01*
Y-140945D01*
X166535Y-141445D01*
X167035D01*
X167535Y-140945D01*
Y-139945D01*
X167035Y-139445D01*
X166036D01*
X165536Y-139945D01*
X168535Y-141945D02*
X169035Y-142444D01*
X170034D01*
X170534Y-141945D01*
Y-141445D01*
X170034Y-140945D01*
X169535D01*
X170034D01*
X170534Y-140445D01*
Y-139945D01*
X170034Y-139445D01*
X169035D01*
X168535Y-139945D01*
X166217Y-134707D02*
X169216D01*
Y-133208D01*
X168716Y-132708D01*
X167717D01*
X167217Y-133208D01*
Y-134707D01*
Y-133708D02*
X166217Y-132708D01*
X169216Y-129709D02*
Y-131708D01*
X167717D01*
X168216Y-130709D01*
Y-130209D01*
X167717Y-129709D01*
X166717D01*
X166217Y-130209D01*
Y-131209D01*
X166717Y-131708D01*
X166217Y-126710D02*
Y-128709D01*
X168216Y-126710D01*
X168716D01*
X169216Y-127210D01*
Y-128209D01*
X168716Y-128709D01*
X188538Y-119628D02*
Y-116629D01*
X187039D01*
X186539Y-117129D01*
Y-118128D01*
X187039Y-118628D01*
X188538D01*
X187539D02*
X186539Y-119628D01*
X183540Y-116629D02*
X185539D01*
Y-118128D01*
X184539Y-117628D01*
X184040D01*
X183540Y-118128D01*
Y-119128D01*
X184040Y-119628D01*
X185039D01*
X185539Y-119128D01*
X182540Y-119628D02*
X181541D01*
X182040D01*
Y-116629D01*
X182540Y-117129D01*
X153482Y-160311D02*
Y-163311D01*
X154981D01*
X155481Y-162811D01*
Y-161811D01*
X154981Y-161311D01*
X153482D01*
X154481D02*
X155481Y-160311D01*
X158480Y-163311D02*
X156481D01*
Y-161811D01*
X157480Y-162311D01*
X157980D01*
X158480Y-161811D01*
Y-160811D01*
X157980Y-160311D01*
X156981D01*
X156481Y-160811D01*
X159480Y-162811D02*
X159979Y-163311D01*
X160979D01*
X161479Y-162811D01*
Y-160811D01*
X160979Y-160311D01*
X159979D01*
X159480Y-160811D01*
Y-162811D01*
X177347Y-114930D02*
X176847Y-114430D01*
Y-113430D01*
X177347Y-112930D01*
X179346D01*
X179846Y-113430D01*
Y-114430D01*
X179346Y-114930D01*
X176847Y-117929D02*
X177347Y-116929D01*
X178347Y-115929D01*
X179346D01*
X179846Y-116429D01*
Y-117429D01*
X179346Y-117929D01*
X178846D01*
X178347Y-117429D01*
Y-115929D01*
X176847Y-118929D02*
Y-120928D01*
X177347D01*
X179346Y-118929D01*
X179846D01*
X383674Y-134303D02*
X383174Y-134803D01*
X382175D01*
X381675Y-134303D01*
Y-132304D01*
X382175Y-131804D01*
X383174D01*
X383674Y-132304D01*
X386673Y-134803D02*
X385673Y-134303D01*
X384674Y-133304D01*
Y-132304D01*
X385174Y-131804D01*
X386173D01*
X386673Y-132304D01*
Y-132804D01*
X386173Y-133304D01*
X384674D01*
X389672Y-134803D02*
X388673Y-134303D01*
X387673Y-133304D01*
Y-132304D01*
X388173Y-131804D01*
X389172D01*
X389672Y-132304D01*
Y-132804D01*
X389172Y-133304D01*
X387673D01*
X144519Y-123480D02*
X145019Y-122980D01*
X146019D01*
X146518Y-123480D01*
Y-125480D01*
X146019Y-125979D01*
X145019D01*
X144519Y-125480D01*
X141520Y-122980D02*
X142520Y-123480D01*
X143519Y-124480D01*
Y-125480D01*
X143019Y-125979D01*
X142020D01*
X141520Y-125480D01*
Y-124980D01*
X142020Y-124480D01*
X143519D01*
X138521Y-122980D02*
X140520D01*
Y-124480D01*
X139521Y-123980D01*
X139021D01*
X138521Y-124480D01*
Y-125480D01*
X139021Y-125979D01*
X140021D01*
X140520Y-125480D01*
X556268Y-346275D02*
X555768Y-346775D01*
X554769D01*
X554269Y-346275D01*
Y-344276D01*
X554769Y-343776D01*
X555768D01*
X556268Y-344276D01*
X559267Y-346775D02*
X558268Y-346275D01*
X557268Y-345276D01*
Y-344276D01*
X557768Y-343776D01*
X558768D01*
X559267Y-344276D01*
Y-344776D01*
X558768Y-345276D01*
X557268D01*
X561767Y-343776D02*
Y-346775D01*
X560267Y-345276D01*
X562266D01*
X564142Y-325015D02*
X563643Y-325515D01*
X562643D01*
X562143Y-325015D01*
Y-323016D01*
X562643Y-322516D01*
X563643D01*
X564142Y-323016D01*
X567141Y-325515D02*
X565142D01*
Y-324016D01*
X566142Y-324516D01*
X566642D01*
X567141Y-324016D01*
Y-323016D01*
X566642Y-322516D01*
X565642D01*
X565142Y-323016D01*
X568141Y-325515D02*
X570140D01*
Y-325015D01*
X568141Y-323016D01*
Y-322516D01*
X556724Y-324197D02*
X557224Y-323697D01*
X558223D01*
X558723Y-324197D01*
Y-326197D01*
X558223Y-326696D01*
X557224D01*
X556724Y-326197D01*
X553725Y-323697D02*
X555724D01*
Y-325197D01*
X554724Y-324697D01*
X554225D01*
X553725Y-325197D01*
Y-326197D01*
X554225Y-326696D01*
X555224D01*
X555724Y-326197D01*
X550726Y-323697D02*
X551725Y-324197D01*
X552725Y-325197D01*
Y-326197D01*
X552225Y-326696D01*
X551226D01*
X550726Y-326197D01*
Y-325697D01*
X551226Y-325197D01*
X552725D01*
X568141Y-302150D02*
X568641Y-301650D01*
X569641D01*
X570140Y-302150D01*
Y-304149D01*
X569641Y-304649D01*
X568641D01*
X568141Y-304149D01*
X565142Y-301650D02*
X567141D01*
Y-303150D01*
X566142Y-302650D01*
X565642D01*
X565142Y-303150D01*
Y-304149D01*
X565642Y-304649D01*
X566642D01*
X567141Y-304149D01*
X562143Y-301650D02*
X564142D01*
Y-303150D01*
X563143Y-302650D01*
X562643D01*
X562143Y-303150D01*
Y-304149D01*
X562643Y-304649D01*
X563643D01*
X564142Y-304149D01*
X118473Y-53756D02*
X117973Y-54255D01*
X116974D01*
X116474Y-53756D01*
Y-51756D01*
X116974Y-51256D01*
X117973D01*
X118473Y-51756D01*
X121472Y-54255D02*
X119473D01*
Y-52756D01*
X120473Y-53256D01*
X120972D01*
X121472Y-52756D01*
Y-51756D01*
X120972Y-51256D01*
X119973D01*
X119473Y-51756D01*
X123971Y-51256D02*
Y-54255D01*
X122472Y-52756D01*
X124471D01*
X169897Y-47669D02*
X170397Y-48169D01*
Y-49168D01*
X169897Y-49668D01*
X167898D01*
X167398Y-49168D01*
Y-48169D01*
X167898Y-47669D01*
X167398Y-45169D02*
X170397D01*
X168898Y-46669D01*
Y-44670D01*
X169897Y-43670D02*
X170397Y-43170D01*
Y-42170D01*
X169897Y-41671D01*
X169397D01*
X168898Y-42170D01*
Y-42670D01*
Y-42170D01*
X168398Y-41671D01*
X167898D01*
X167398Y-42170D01*
Y-43170D01*
X167898Y-43670D01*
X123591Y-81708D02*
X123091Y-82208D01*
X122092D01*
X121592Y-81708D01*
Y-79709D01*
X122092Y-79209D01*
X123091D01*
X123591Y-79709D01*
X126090Y-79209D02*
Y-82208D01*
X124591Y-80709D01*
X126590D01*
X129589Y-79209D02*
X127590D01*
X129589Y-81208D01*
Y-81708D01*
X129089Y-82208D01*
X128090D01*
X127590Y-81708D01*
X143471Y-47066D02*
X143970Y-47566D01*
Y-48566D01*
X143471Y-49065D01*
X141471D01*
X140971Y-48566D01*
Y-47566D01*
X141471Y-47066D01*
X140971Y-44567D02*
X143970D01*
X142471Y-46066D01*
Y-44067D01*
X140971Y-43067D02*
Y-42068D01*
Y-42568D01*
X143970D01*
X143471Y-43067D01*
X39702Y-153225D02*
Y-156224D01*
X41202D01*
X41701Y-155724D01*
Y-154724D01*
X41202Y-154225D01*
X39702D01*
X40702D02*
X41701Y-153225D01*
X44201D02*
Y-156224D01*
X42701Y-154724D01*
X44701D01*
X45700Y-155724D02*
X46200Y-156224D01*
X47200D01*
X47699Y-155724D01*
Y-155224D01*
X47200Y-154724D01*
X47699Y-154225D01*
Y-153725D01*
X47200Y-153225D01*
X46200D01*
X45700Y-153725D01*
Y-154225D01*
X46200Y-154724D01*
X45700Y-155224D01*
Y-155724D01*
X46200Y-154724D02*
X47200D01*
X43369Y-5830D02*
Y-2831D01*
X41869D01*
X41369Y-3331D01*
Y-4331D01*
X41869Y-4831D01*
X43369D01*
X42369D02*
X41369Y-5830D01*
X40370Y-3331D02*
X39870Y-2831D01*
X38870D01*
X38370Y-3331D01*
Y-3831D01*
X38870Y-4331D01*
X39370D01*
X38870D01*
X38370Y-4831D01*
Y-5330D01*
X38870Y-5830D01*
X39870D01*
X40370Y-5330D01*
X37371D02*
X36871Y-5830D01*
X35871D01*
X35371Y-5330D01*
Y-3331D01*
X35871Y-2831D01*
X36871D01*
X37371Y-3331D01*
Y-3831D01*
X36871Y-4331D01*
X35371D01*
X45337Y469D02*
Y3468D01*
X43838D01*
X43338Y2968D01*
Y1969D01*
X43838Y1469D01*
X45337D01*
X44338D02*
X43338Y469D01*
X42338Y2968D02*
X41838Y3468D01*
X40839D01*
X40339Y2968D01*
Y2468D01*
X40839Y1969D01*
X41339D01*
X40839D01*
X40339Y1469D01*
Y969D01*
X40839Y469D01*
X41838D01*
X42338Y969D01*
X39339Y2968D02*
X38839Y3468D01*
X37840D01*
X37340Y2968D01*
Y2468D01*
X37840Y1969D01*
X37340Y1469D01*
Y969D01*
X37840Y469D01*
X38839D01*
X39339Y969D01*
Y1469D01*
X38839Y1969D01*
X39339Y2468D01*
Y2968D01*
X38839Y1969D02*
X37840D01*
X45337Y7556D02*
Y10555D01*
X43838D01*
X43338Y10055D01*
Y9055D01*
X43838Y8555D01*
X45337D01*
X44338D02*
X43338Y7556D01*
X42338Y10055D02*
X41838Y10555D01*
X40839D01*
X40339Y10055D01*
Y9555D01*
X40839Y9055D01*
X41339D01*
X40839D01*
X40339Y8555D01*
Y8055D01*
X40839Y7556D01*
X41838D01*
X42338Y8055D01*
X37340Y10555D02*
X38339Y10055D01*
X39339Y9055D01*
Y8055D01*
X38839Y7556D01*
X37840D01*
X37340Y8055D01*
Y8555D01*
X37840Y9055D01*
X39339D01*
X45731Y14248D02*
Y17248D01*
X44232D01*
X43732Y16748D01*
Y15748D01*
X44232Y15248D01*
X45731D01*
X44731D02*
X43732Y14248D01*
X42732Y16748D02*
X42232Y17248D01*
X41232D01*
X40733Y16748D01*
Y16248D01*
X41232Y15748D01*
X41732D01*
X41232D01*
X40733Y15248D01*
Y14748D01*
X41232Y14248D01*
X42232D01*
X42732Y14748D01*
X37734Y17248D02*
X39733D01*
Y15748D01*
X38733Y16248D01*
X38233D01*
X37734Y15748D01*
Y14748D01*
X38233Y14248D01*
X39233D01*
X39733Y14748D01*
X156481Y-89339D02*
X155981Y-88839D01*
Y-87840D01*
X156481Y-87340D01*
X158480D01*
X158980Y-87840D01*
Y-88839D01*
X158480Y-89339D01*
X156481Y-90339D02*
X155981Y-90839D01*
Y-91838D01*
X156481Y-92338D01*
X156981D01*
X157480Y-91838D01*
Y-91339D01*
Y-91838D01*
X157980Y-92338D01*
X158480D01*
X158980Y-91838D01*
Y-90839D01*
X158480Y-90339D01*
X156481Y-93338D02*
X155981Y-93838D01*
Y-94837D01*
X156481Y-95337D01*
X156981D01*
X157480Y-94837D01*
Y-94338D01*
Y-94837D01*
X157980Y-95337D01*
X158480D01*
X158980Y-94837D01*
Y-93838D01*
X158480Y-93338D01*
X434278Y-188521D02*
X431279D01*
Y-190021D01*
X431779Y-190520D01*
X432779D01*
X433279Y-190021D01*
Y-188521D01*
Y-189521D02*
X434278Y-190520D01*
X431779Y-191520D02*
X431279Y-192020D01*
Y-193019D01*
X431779Y-193519D01*
X432279D01*
X432779Y-193019D01*
Y-192520D01*
Y-193019D01*
X433279Y-193519D01*
X433779D01*
X434278Y-193019D01*
Y-192020D01*
X433779Y-191520D01*
X431279Y-194519D02*
Y-196518D01*
X431779D01*
X433779Y-194519D01*
X434278D01*
X530678Y-345094D02*
X530178Y-345594D01*
X529178D01*
X528679Y-345094D01*
Y-343095D01*
X529178Y-342595D01*
X530178D01*
X530678Y-343095D01*
X531677Y-345094D02*
X532177Y-345594D01*
X533177D01*
X533677Y-345094D01*
Y-344594D01*
X533177Y-344094D01*
X532677D01*
X533177D01*
X533677Y-343595D01*
Y-343095D01*
X533177Y-342595D01*
X532177D01*
X531677Y-343095D01*
X534677Y-345594D02*
X536676D01*
Y-345094D01*
X534677Y-343095D01*
Y-342595D01*
X535858Y-294276D02*
X536357Y-293776D01*
X537357D01*
X537857Y-294276D01*
Y-296275D01*
X537357Y-296775D01*
X536357D01*
X535858Y-296275D01*
X534858Y-294276D02*
X534358Y-293776D01*
X533358D01*
X532859Y-294276D01*
Y-294776D01*
X533358Y-295276D01*
X533858D01*
X533358D01*
X532859Y-295775D01*
Y-296275D01*
X533358Y-296775D01*
X534358D01*
X534858Y-296275D01*
X529860Y-293776D02*
X530859Y-294276D01*
X531859Y-295276D01*
Y-296275D01*
X531359Y-296775D01*
X530359D01*
X529860Y-296275D01*
Y-295775D01*
X530359Y-295276D01*
X531859D01*
X534992Y-321564D02*
X535492Y-321064D01*
X536492D01*
X536992Y-321564D01*
Y-323563D01*
X536492Y-324063D01*
X535492D01*
X534992Y-323563D01*
X533992Y-321564D02*
X533493Y-321064D01*
X532493D01*
X531993Y-321564D01*
Y-322063D01*
X532493Y-322563D01*
X532993D01*
X532493D01*
X531993Y-323063D01*
Y-323563D01*
X532493Y-324063D01*
X533493D01*
X533992Y-323563D01*
X528994Y-321064D02*
X530994D01*
Y-322563D01*
X529994Y-322063D01*
X529494D01*
X528994Y-322563D01*
Y-323563D01*
X529494Y-324063D01*
X530494D01*
X530994Y-323563D01*
X530993Y-318716D02*
X530493Y-319216D01*
X529494D01*
X528994Y-318716D01*
Y-316717D01*
X529494Y-316217D01*
X530493D01*
X530993Y-316717D01*
X531993Y-318716D02*
X532493Y-319216D01*
X533493D01*
X533992Y-318716D01*
Y-318216D01*
X533493Y-317717D01*
X532993D01*
X533493D01*
X533992Y-317217D01*
Y-316717D01*
X533493Y-316217D01*
X532493D01*
X531993Y-316717D01*
X536492Y-316217D02*
Y-319216D01*
X534992Y-317717D01*
X536991D01*
X54800Y-45337D02*
X57799D01*
Y-43838D01*
X57299Y-43338D01*
X56299D01*
X55799Y-43838D01*
Y-45337D01*
Y-44338D02*
X54800Y-43338D01*
Y-40339D02*
Y-42338D01*
X56799Y-40339D01*
X57299D01*
X57799Y-40839D01*
Y-41838D01*
X57299Y-42338D01*
X57799Y-39339D02*
Y-37340D01*
X57299D01*
X55300Y-39339D01*
X54800D01*
X62660Y-23547D02*
Y-20548D01*
X61161D01*
X60661Y-21048D01*
Y-22047D01*
X61161Y-22547D01*
X62660D01*
X61660D02*
X60661Y-23547D01*
X57662D02*
X59661D01*
X57662Y-21547D01*
Y-21048D01*
X58162Y-20548D01*
X59161D01*
X59661Y-21048D01*
X54663Y-20548D02*
X55662Y-21048D01*
X56662Y-22047D01*
Y-23047D01*
X56162Y-23547D01*
X55163D01*
X54663Y-23047D01*
Y-22547D01*
X55163Y-22047D01*
X56662D01*
X36032Y-296775D02*
Y-293776D01*
X34533D01*
X34033Y-294276D01*
Y-295276D01*
X34533Y-295775D01*
X36032D01*
X35033D02*
X34033Y-296775D01*
X33033D02*
X32034D01*
X32533D01*
Y-293776D01*
X33033Y-294276D01*
X30534Y-293776D02*
X28535D01*
Y-294276D01*
X30534Y-296275D01*
Y-296775D01*
X205324Y-127090D02*
Y-124091D01*
X203824D01*
X203324Y-124591D01*
Y-125591D01*
X203824Y-126090D01*
X205324D01*
X204324D02*
X203324Y-127090D01*
X202325D02*
X201325D01*
X201825D01*
Y-124091D01*
X202325Y-124591D01*
X197826Y-127090D02*
X199825D01*
X197826Y-125091D01*
Y-124591D01*
X198326Y-124091D01*
X199326D01*
X199825Y-124591D01*
X239076Y-128271D02*
Y-125272D01*
X237576D01*
X237076Y-125772D01*
Y-126772D01*
X237576Y-127271D01*
X239076D01*
X238076D02*
X237076Y-128271D01*
X236077D02*
X235077D01*
X235577D01*
Y-125272D01*
X236077Y-125772D01*
X233577Y-128271D02*
X232578D01*
X233078D01*
Y-125272D01*
X233577Y-125772D01*
X229339Y-129059D02*
Y-126059D01*
X227840D01*
X227340Y-126559D01*
Y-127559D01*
X227840Y-128059D01*
X229339D01*
X228340D02*
X227340Y-129059D01*
X226340D02*
X225341D01*
X225840D01*
Y-126059D01*
X226340Y-126559D01*
X223841D02*
X223341Y-126059D01*
X222342D01*
X221842Y-126559D01*
Y-128559D01*
X222342Y-129059D01*
X223341D01*
X223841Y-128559D01*
Y-126559D01*
X197275Y-105299D02*
X197775Y-104800D01*
X198775D01*
X199274Y-105299D01*
Y-107299D01*
X198775Y-107799D01*
X197775D01*
X197275Y-107299D01*
X194276Y-107799D02*
X196275D01*
X194276Y-105799D01*
Y-105299D01*
X194776Y-104800D01*
X195775D01*
X196275Y-105299D01*
X191777Y-107799D02*
Y-104800D01*
X193276Y-106299D01*
X191277D01*
X218079Y-145488D02*
X217580Y-145988D01*
X216580D01*
X216080Y-145488D01*
Y-143489D01*
X216580Y-142989D01*
X217580D01*
X218079Y-143489D01*
X221078Y-142989D02*
X219079D01*
X221078Y-144988D01*
Y-145488D01*
X220579Y-145988D01*
X219579D01*
X219079Y-145488D01*
X222078D02*
X222578Y-145988D01*
X223578D01*
X224077Y-145488D01*
Y-144988D01*
X223578Y-144488D01*
X223078D01*
X223578D01*
X224077Y-143988D01*
Y-143489D01*
X223578Y-142989D01*
X222578D01*
X222078Y-143489D01*
X424741Y-184763D02*
X424242Y-184263D01*
Y-183263D01*
X424741Y-182764D01*
X426741D01*
X427241Y-183263D01*
Y-184263D01*
X426741Y-184763D01*
X427241Y-187762D02*
Y-185763D01*
X425241Y-187762D01*
X424741D01*
X424242Y-187262D01*
Y-186262D01*
X424741Y-185763D01*
X424242Y-190761D02*
Y-188762D01*
X425741D01*
X425241Y-189761D01*
Y-190261D01*
X425741Y-190761D01*
X426741D01*
X427241Y-190261D01*
Y-189261D01*
X426741Y-188762D01*
X19610Y-281684D02*
X16611D01*
Y-283184D01*
X17111Y-283684D01*
X18110D01*
X18610Y-283184D01*
Y-281684D01*
Y-282684D02*
X19610Y-283684D01*
Y-284683D02*
Y-285683D01*
Y-285183D01*
X16611D01*
X17111Y-284683D01*
X16611Y-289182D02*
X17111Y-288182D01*
X18110Y-287182D01*
X19110D01*
X19610Y-287682D01*
Y-288682D01*
X19110Y-289182D01*
X18610D01*
X18110Y-288682D01*
Y-287182D01*
X10161Y-175779D02*
X7162D01*
Y-177278D01*
X7662Y-177778D01*
X8661D01*
X9161Y-177278D01*
Y-175779D01*
Y-176778D02*
X10161Y-177778D01*
Y-178778D02*
Y-179778D01*
Y-179278D01*
X7162D01*
X7662Y-178778D01*
X7162Y-183276D02*
Y-181277D01*
X8661D01*
X8162Y-182277D01*
Y-182776D01*
X8661Y-183276D01*
X9661D01*
X10161Y-182776D01*
Y-181777D01*
X9661Y-181277D01*
X88976Y-20866D02*
Y-23865D01*
X90476D01*
X90976Y-23365D01*
Y-22366D01*
X90476Y-21866D01*
X88976D01*
X89976D02*
X90976Y-20866D01*
X93975Y-23865D02*
X91975D01*
Y-22366D01*
X92975Y-22865D01*
X93475D01*
X93975Y-22366D01*
Y-21366D01*
X93475Y-20866D01*
X92475D01*
X91975Y-21366D01*
X294724Y-269685D02*
Y-266686D01*
X293225D01*
X292725Y-267186D01*
Y-268185D01*
X293225Y-268685D01*
X294724D01*
X293725D02*
X292725Y-269685D01*
X289726D02*
X291725D01*
X289726Y-267686D01*
Y-267186D01*
X290226Y-266686D01*
X291226D01*
X291725Y-267186D01*
X286727Y-269685D02*
X288726D01*
X286727Y-267686D01*
Y-267186D01*
X287227Y-266686D01*
X288227D01*
X288726Y-267186D01*
X66142Y-3543D02*
Y-544D01*
X64642D01*
X64142Y-1044D01*
Y-2044D01*
X64642Y-2544D01*
X66142D01*
X65142D02*
X64142Y-3543D01*
X63143Y-3043D02*
X62643Y-3543D01*
X61643D01*
X61143Y-3043D01*
Y-1044D01*
X61643Y-544D01*
X62643D01*
X63143Y-1044D01*
Y-1544D01*
X62643Y-2044D01*
X61143D01*
X56693Y-3305D02*
Y-306D01*
X55193D01*
X54694Y-806D01*
Y-1806D01*
X55193Y-2306D01*
X56693D01*
X55693D02*
X54694Y-3305D01*
X51695Y-306D02*
X52694Y-806D01*
X53694Y-1806D01*
Y-2805D01*
X53194Y-3305D01*
X52194D01*
X51695Y-2805D01*
Y-2306D01*
X52194Y-1806D01*
X53694D01*
X93701Y-10236D02*
Y-7237D01*
X92201D01*
X91701Y-7737D01*
Y-8737D01*
X92201Y-9236D01*
X93701D01*
X92701D02*
X91701Y-10236D01*
X89202D02*
Y-7237D01*
X90702Y-8737D01*
X88702D01*
X106299Y-31890D02*
Y-28891D01*
X104800D01*
X104300Y-29391D01*
Y-30390D01*
X104800Y-30890D01*
X106299D01*
X105299D02*
X104300Y-31890D01*
X103300Y-29391D02*
X102800Y-28891D01*
X101801D01*
X101301Y-29391D01*
Y-29890D01*
X101801Y-30390D01*
X102301D01*
X101801D01*
X101301Y-30890D01*
Y-31390D01*
X101801Y-31890D01*
X102800D01*
X103300Y-31390D01*
X106299Y-20866D02*
X103300D01*
Y-22366D01*
X103800Y-22865D01*
X104800D01*
X105299Y-22366D01*
Y-20866D01*
Y-21866D02*
X106299Y-22865D01*
Y-25864D02*
Y-23865D01*
X104300Y-25864D01*
X103800D01*
X103300Y-25365D01*
Y-24365D01*
X103800Y-23865D01*
X128883Y-58124D02*
X129383Y-57624D01*
X130382D01*
X130882Y-58124D01*
Y-60123D01*
X130382Y-60623D01*
X129383D01*
X128883Y-60123D01*
X125884Y-57624D02*
X126883Y-58124D01*
X127883Y-59124D01*
Y-60123D01*
X127383Y-60623D01*
X126384D01*
X125884Y-60123D01*
Y-59623D01*
X126384Y-59124D01*
X127883D01*
X124884Y-60623D02*
X123884D01*
X124384D01*
Y-57624D01*
X124884Y-58124D01*
X123985Y-29784D02*
X124485Y-29284D01*
X125484D01*
X125984Y-29784D01*
Y-31784D01*
X125484Y-32283D01*
X124485D01*
X123985Y-31784D01*
X120986Y-29284D02*
X121985Y-29784D01*
X122985Y-30784D01*
Y-31784D01*
X122485Y-32283D01*
X121486D01*
X120986Y-31784D01*
Y-31284D01*
X121486Y-30784D01*
X122985D01*
X119986Y-29784D02*
X119486Y-29284D01*
X118487D01*
X117987Y-29784D01*
Y-31784D01*
X118487Y-32283D01*
X119486D01*
X119986Y-31784D01*
Y-29784D01*
X146045Y-86751D02*
X145545Y-87251D01*
X144546D01*
X144046Y-86751D01*
Y-84752D01*
X144546Y-84252D01*
X145545D01*
X146045Y-84752D01*
X149044Y-87251D02*
X147045D01*
Y-85751D01*
X148045Y-86251D01*
X148544D01*
X149044Y-85751D01*
Y-84752D01*
X148544Y-84252D01*
X147545D01*
X147045Y-84752D01*
X150044D02*
X150544Y-84252D01*
X151543D01*
X152043Y-84752D01*
Y-86751D01*
X151543Y-87251D01*
X150544D01*
X150044Y-86751D01*
Y-86251D01*
X150544Y-85751D01*
X152043D01*
X151544Y-63643D02*
X152044Y-63143D01*
X153043D01*
X153543Y-63643D01*
Y-65642D01*
X153043Y-66142D01*
X152044D01*
X151544Y-65642D01*
X148545Y-63143D02*
X150544D01*
Y-64642D01*
X149545Y-64142D01*
X149045D01*
X148545Y-64642D01*
Y-65642D01*
X149045Y-66142D01*
X150044D01*
X150544Y-65642D01*
X147545Y-63643D02*
X147045Y-63143D01*
X146046D01*
X145546Y-63643D01*
Y-64142D01*
X146046Y-64642D01*
X145546Y-65142D01*
Y-65642D01*
X146046Y-66142D01*
X147045D01*
X147545Y-65642D01*
Y-65142D01*
X147045Y-64642D01*
X147545Y-64142D01*
Y-63643D01*
X147045Y-64642D02*
X146046D01*
X276491Y-369099D02*
X276991Y-369599D01*
Y-370598D01*
X276491Y-371098D01*
X274492D01*
X273992Y-370598D01*
Y-369599D01*
X274492Y-369099D01*
X276991Y-366100D02*
Y-368099D01*
X275491D01*
X275991Y-367099D01*
Y-366599D01*
X275491Y-366100D01*
X274492D01*
X273992Y-366599D01*
Y-367599D01*
X274492Y-368099D01*
X276491Y-365100D02*
X276991Y-364600D01*
Y-363600D01*
X276491Y-363101D01*
X275991D01*
X275491Y-363600D01*
Y-364100D01*
Y-363600D01*
X274991Y-363101D01*
X274492D01*
X273992Y-363600D01*
Y-364600D01*
X274492Y-365100D01*
X269891Y-369099D02*
X270391Y-369599D01*
Y-370598D01*
X269891Y-371098D01*
X267892D01*
X267392Y-370598D01*
Y-369599D01*
X267892Y-369099D01*
X270391Y-366100D02*
Y-368099D01*
X268891D01*
X269391Y-367099D01*
Y-366599D01*
X268891Y-366100D01*
X267892D01*
X267392Y-366599D01*
Y-367599D01*
X267892Y-368099D01*
X267392Y-363101D02*
Y-365100D01*
X269391Y-363101D01*
X269891D01*
X270391Y-363600D01*
Y-364600D01*
X269891Y-365100D01*
X260391Y-369099D02*
X260891Y-369599D01*
Y-370598D01*
X260391Y-371098D01*
X258391D01*
X257892Y-370598D01*
Y-369599D01*
X258391Y-369099D01*
X260891Y-366100D02*
Y-368099D01*
X259391D01*
X259891Y-367099D01*
Y-366599D01*
X259391Y-366100D01*
X258391D01*
X257892Y-366599D01*
Y-367599D01*
X258391Y-368099D01*
X257892Y-365100D02*
Y-364100D01*
Y-364600D01*
X260891D01*
X260391Y-365100D01*
X253291Y-369099D02*
X253791Y-369599D01*
Y-370598D01*
X253291Y-371098D01*
X251291D01*
X250792Y-370598D01*
Y-369599D01*
X251291Y-369099D01*
X253791Y-366100D02*
Y-368099D01*
X252291D01*
X252791Y-367099D01*
Y-366599D01*
X252291Y-366100D01*
X251291D01*
X250792Y-366599D01*
Y-367599D01*
X251291Y-368099D01*
X253291Y-365100D02*
X253791Y-364600D01*
Y-363600D01*
X253291Y-363101D01*
X251291D01*
X250792Y-363600D01*
Y-364600D01*
X251291Y-365100D01*
X253291D01*
X244191Y-369099D02*
X244691Y-369599D01*
Y-370598D01*
X244191Y-371098D01*
X242192D01*
X241692Y-370598D01*
Y-369599D01*
X242192Y-369099D01*
X241692Y-366599D02*
X244691D01*
X243191Y-368099D01*
Y-366100D01*
X242192Y-365100D02*
X241692Y-364600D01*
Y-363600D01*
X242192Y-363101D01*
X244191D01*
X244691Y-363600D01*
Y-364600D01*
X244191Y-365100D01*
X243691D01*
X243191Y-364600D01*
Y-363101D01*
X237391Y-369099D02*
X237891Y-369599D01*
Y-370598D01*
X237391Y-371098D01*
X235391D01*
X234892Y-370598D01*
Y-369599D01*
X235391Y-369099D01*
X234892Y-366599D02*
X237891D01*
X236391Y-368099D01*
Y-366100D01*
X237391Y-365100D02*
X237891Y-364600D01*
Y-363600D01*
X237391Y-363101D01*
X236891D01*
X236391Y-363600D01*
X235891Y-363101D01*
X235391D01*
X234892Y-363600D01*
Y-364600D01*
X235391Y-365100D01*
X235891D01*
X236391Y-364600D01*
X236891Y-365100D01*
X237391D01*
X236391Y-364600D02*
Y-363600D01*
X225891Y-369099D02*
X226391Y-369599D01*
Y-370598D01*
X225891Y-371098D01*
X223891D01*
X223392Y-370598D01*
Y-369599D01*
X223891Y-369099D01*
X223392Y-366599D02*
X226391D01*
X224891Y-368099D01*
Y-366100D01*
X226391Y-365100D02*
Y-363101D01*
X225891D01*
X223891Y-365100D01*
X223392D01*
X218991Y-369099D02*
X219491Y-369599D01*
Y-370598D01*
X218991Y-371098D01*
X216991D01*
X216492Y-370598D01*
Y-369599D01*
X216991Y-369099D01*
X216492Y-366599D02*
X219491D01*
X217991Y-368099D01*
Y-366100D01*
X219491Y-363101D02*
X218991Y-364100D01*
X217991Y-365100D01*
X216991D01*
X216492Y-364600D01*
Y-363600D01*
X216991Y-363101D01*
X217491D01*
X217991Y-363600D01*
Y-365100D01*
X211554Y-367439D02*
X212054Y-367939D01*
Y-368939D01*
X211554Y-369439D01*
X209555D01*
X209055Y-368939D01*
Y-367939D01*
X209555Y-367439D01*
X209055Y-364940D02*
X212054D01*
X210555Y-366440D01*
Y-364440D01*
X212054Y-361441D02*
Y-363440D01*
X210555D01*
X211054Y-362441D01*
Y-361941D01*
X210555Y-361441D01*
X209555D01*
X209055Y-361941D01*
Y-362941D01*
X209555Y-363440D01*
X204566Y-367242D02*
X205066Y-367742D01*
Y-368742D01*
X204566Y-369242D01*
X202567D01*
X202067Y-368742D01*
Y-367742D01*
X202567Y-367242D01*
X202067Y-364743D02*
X205066D01*
X203567Y-366243D01*
Y-364243D01*
X202067Y-361744D02*
X205066D01*
X203567Y-363244D01*
Y-361244D01*
X72578Y-57843D02*
X73078Y-58343D01*
Y-59343D01*
X72578Y-59842D01*
X70579D01*
X70079Y-59343D01*
Y-58343D01*
X70579Y-57843D01*
X70079Y-54844D02*
Y-56844D01*
X72078Y-54844D01*
X72578D01*
X73078Y-55344D01*
Y-56344D01*
X72578Y-56844D01*
X70079Y-51845D02*
Y-53844D01*
X72078Y-51845D01*
X72578D01*
X73078Y-52345D01*
Y-53345D01*
X72578Y-53844D01*
X55755Y-57071D02*
X56255Y-57571D01*
Y-58571D01*
X55755Y-59070D01*
X53756D01*
X53256Y-58571D01*
Y-57571D01*
X53756Y-57071D01*
X53256Y-54072D02*
Y-56071D01*
X55255Y-54072D01*
X55755D01*
X56255Y-54572D01*
Y-55572D01*
X55755Y-56071D01*
X53256Y-53072D02*
Y-52073D01*
Y-52573D01*
X56255D01*
X55755Y-53072D01*
X618283Y-66464D02*
X617783Y-66964D01*
X616783D01*
X616284Y-66464D01*
Y-64464D01*
X616783Y-63965D01*
X617783D01*
X618283Y-64464D01*
X621282Y-63965D02*
X619282D01*
X621282Y-65964D01*
Y-66464D01*
X620782Y-66964D01*
X619782D01*
X619282Y-66464D01*
X622282D02*
X622781Y-66964D01*
X623781D01*
X624281Y-66464D01*
Y-64464D01*
X623781Y-63965D01*
X622781D01*
X622282Y-64464D01*
Y-66464D01*
X613142Y-52481D02*
X613642Y-51981D01*
X614642D01*
X615142Y-52481D01*
Y-54480D01*
X614642Y-54980D01*
X613642D01*
X613142Y-54480D01*
X612143Y-54980D02*
X611143D01*
X611643D01*
Y-51981D01*
X612143Y-52481D01*
X609644Y-54480D02*
X609144Y-54980D01*
X608144D01*
X607644Y-54480D01*
Y-52481D01*
X608144Y-51981D01*
X609144D01*
X609644Y-52481D01*
Y-52981D01*
X609144Y-53481D01*
X607644D01*
X108131Y-52787D02*
X107631Y-52287D01*
Y-51287D01*
X108131Y-50787D01*
X110130D01*
X110630Y-51287D01*
Y-52287D01*
X110130Y-52787D01*
X110630Y-53786D02*
Y-54786D01*
Y-54286D01*
X107631D01*
X108131Y-53786D01*
Y-56286D02*
X107631Y-56786D01*
Y-57785D01*
X108131Y-58285D01*
X108631D01*
X109130Y-57785D01*
X109630Y-58285D01*
X110130D01*
X110630Y-57785D01*
Y-56786D01*
X110130Y-56286D01*
X109630D01*
X109130Y-56786D01*
X108631Y-56286D01*
X108131D01*
X109130Y-56786D02*
Y-57785D01*
X96820Y-69942D02*
X97319Y-69442D01*
X98319D01*
X98819Y-69942D01*
Y-71941D01*
X98319Y-72441D01*
X97319D01*
X96820Y-71941D01*
X95820Y-72441D02*
X94820D01*
X95320D01*
Y-69442D01*
X95820Y-69942D01*
X93321Y-69442D02*
X91321D01*
Y-69942D01*
X93321Y-71941D01*
Y-72441D01*
X96987Y-57843D02*
X97487Y-58343D01*
Y-59343D01*
X96987Y-59842D01*
X94988D01*
X94488Y-59343D01*
Y-58343D01*
X94988Y-57843D01*
X94488Y-56844D02*
Y-55844D01*
Y-56344D01*
X97487D01*
X96987Y-56844D01*
X97487Y-52345D02*
X96987Y-53345D01*
X95988Y-54344D01*
X94988D01*
X94488Y-53844D01*
Y-52845D01*
X94988Y-52345D01*
X95488D01*
X95988Y-52845D01*
Y-54344D01*
X101044Y-53574D02*
X100544Y-53074D01*
Y-52075D01*
X101044Y-51575D01*
X103043D01*
X103543Y-52075D01*
Y-53074D01*
X103043Y-53574D01*
X103543Y-54574D02*
Y-55573D01*
Y-55074D01*
X100544D01*
X101044Y-54574D01*
X100544Y-59072D02*
Y-57073D01*
X102044D01*
X101544Y-58073D01*
Y-58573D01*
X102044Y-59072D01*
X103043D01*
X103543Y-58573D01*
Y-57573D01*
X103043Y-57073D01*
X145926Y-100818D02*
X145426Y-100318D01*
Y-99319D01*
X145926Y-98819D01*
X147925D01*
X148425Y-99319D01*
Y-100318D01*
X147925Y-100818D01*
Y-101818D02*
X148425Y-102318D01*
Y-103317D01*
X147925Y-103817D01*
X145926D01*
X145426Y-103317D01*
Y-102318D01*
X145926Y-101818D01*
X146426D01*
X146926Y-102318D01*
Y-103817D01*
X164036Y-91763D02*
X163536Y-91263D01*
Y-90264D01*
X164036Y-89764D01*
X166036D01*
X166535Y-90264D01*
Y-91263D01*
X166036Y-91763D01*
X163536Y-94762D02*
X164036Y-93762D01*
X165036Y-92763D01*
X166036D01*
X166535Y-93263D01*
Y-94262D01*
X166036Y-94762D01*
X165536D01*
X165036Y-94262D01*
Y-92763D01*
X415717Y-117579D02*
X416217Y-117080D01*
X417217D01*
X417717Y-117579D01*
Y-119579D01*
X417217Y-120079D01*
X416217D01*
X415717Y-119579D01*
X412718Y-117080D02*
X414717D01*
Y-118579D01*
X413718Y-118079D01*
X413218D01*
X412718Y-118579D01*
Y-119579D01*
X413218Y-120079D01*
X414218D01*
X414717Y-119579D01*
X113355Y-8918D02*
X113855Y-8418D01*
X114855D01*
X115354Y-8918D01*
Y-10917D01*
X114855Y-11417D01*
X113855D01*
X113355Y-10917D01*
X112355Y-8918D02*
X111855Y-8418D01*
X110856D01*
X110356Y-8918D01*
Y-9418D01*
X110856Y-9918D01*
X111356D01*
X110856D01*
X110356Y-10418D01*
Y-10917D01*
X110856Y-11417D01*
X111855D01*
X112355Y-10917D01*
D25*
X561874Y-233603D02*
X562873D01*
X563373Y-234102D01*
Y-236102D01*
X562873Y-236602D01*
X561874D01*
X561374Y-236102D01*
Y-234102D01*
X561874Y-233603D01*
X558375Y-234102D02*
X558875Y-233603D01*
X559874D01*
X560374Y-234102D01*
Y-234602D01*
X559874Y-235102D01*
X558875D01*
X558375Y-235602D01*
Y-236102D01*
X558875Y-236602D01*
X559874D01*
X560374Y-236102D01*
X555376Y-234102D02*
X555876Y-233603D01*
X556875D01*
X557375Y-234102D01*
Y-236102D01*
X556875Y-236602D01*
X555876D01*
X555376Y-236102D01*
X549378Y-234102D02*
X549878Y-233603D01*
X550877D01*
X551377Y-234102D01*
Y-234602D01*
X550877Y-235102D01*
X549878D01*
X549378Y-235602D01*
Y-236102D01*
X549878Y-236602D01*
X550877D01*
X551377Y-236102D01*
X546879Y-236602D02*
X547878D01*
X548378Y-236102D01*
Y-235102D01*
X547878Y-234602D01*
X546879D01*
X546379Y-235102D01*
Y-235602D01*
X548378D01*
X545379Y-234602D02*
Y-236602D01*
Y-235602D01*
X544879Y-235102D01*
X544379Y-234602D01*
X543880D01*
X542380Y-236602D02*
X541380D01*
X541880D01*
Y-234602D01*
X542380D01*
X539381D02*
X538381D01*
X537882Y-235102D01*
Y-236602D01*
X539381D01*
X539881Y-236102D01*
X539381Y-235602D01*
X537882D01*
X536882Y-236602D02*
X535882D01*
X536382D01*
Y-233603D01*
X536882D01*
X529384Y-234102D02*
X529884Y-233603D01*
X530884D01*
X531384Y-234102D01*
Y-234602D01*
X530884Y-235102D01*
X529884D01*
X529384Y-235602D01*
Y-236102D01*
X529884Y-236602D01*
X530884D01*
X531384Y-236102D01*
X526885Y-236602D02*
X527885D01*
X528385Y-236102D01*
Y-235102D01*
X527885Y-234602D01*
X526885D01*
X526385Y-235102D01*
Y-235602D01*
X528385D01*
X525386Y-236602D02*
X524386D01*
X524886D01*
Y-233603D01*
X525386D01*
X521387Y-236602D02*
X522387D01*
X522886Y-236102D01*
Y-235102D01*
X522387Y-234602D01*
X521387D01*
X520887Y-235102D01*
Y-235602D01*
X522886D01*
X517888Y-234602D02*
X519387D01*
X519887Y-235102D01*
Y-236102D01*
X519387Y-236602D01*
X517888D01*
X516388Y-234102D02*
Y-234602D01*
X516888D01*
X515889D01*
X516388D01*
Y-236102D01*
X515889Y-236602D01*
X564161Y-191870D02*
Y-194369D01*
X563661Y-194869D01*
X562661D01*
X562161Y-194369D01*
Y-191870D01*
X561162Y-194869D02*
Y-192870D01*
X560162Y-191870D01*
X559162Y-192870D01*
Y-194869D01*
Y-193370D01*
X561162D01*
X558163Y-194869D02*
Y-191870D01*
X556663D01*
X556163Y-192370D01*
Y-193370D01*
X556663Y-193870D01*
X558163D01*
X557163D02*
X556163Y-194869D01*
X555164Y-191870D02*
X553164D01*
X554164D01*
Y-194869D01*
X547166Y-192370D02*
X547666Y-191870D01*
X548666D01*
X549165Y-192370D01*
Y-192870D01*
X548666Y-193370D01*
X547666D01*
X547166Y-193870D01*
Y-194369D01*
X547666Y-194869D01*
X548666D01*
X549165Y-194369D01*
X544667Y-194869D02*
X545667D01*
X546167Y-194369D01*
Y-193370D01*
X545667Y-192870D01*
X544667D01*
X544167Y-193370D01*
Y-193870D01*
X546167D01*
X543167Y-194869D02*
X542168D01*
X542668D01*
Y-191870D01*
X543167D01*
X539169Y-194869D02*
X540168D01*
X540668Y-194369D01*
Y-193370D01*
X540168Y-192870D01*
X539169D01*
X538669Y-193370D01*
Y-193870D01*
X540668D01*
X535670Y-192870D02*
X537169D01*
X537669Y-193370D01*
Y-194369D01*
X537169Y-194869D01*
X535670D01*
X534170Y-192370D02*
Y-192870D01*
X534670D01*
X533671D01*
X534170D01*
Y-194369D01*
X533671Y-194869D01*
X563309Y-218821D02*
Y-215822D01*
X561810D01*
X561310Y-216322D01*
Y-217322D01*
X561810Y-217821D01*
X563309D01*
X560310Y-218821D02*
Y-215822D01*
X558811D01*
X558311Y-216322D01*
Y-217322D01*
X558811Y-217821D01*
X560310D01*
X555312Y-216322D02*
X555812Y-215822D01*
X556811D01*
X557311Y-216322D01*
Y-216822D01*
X556811Y-217322D01*
X555812D01*
X555312Y-217821D01*
Y-218321D01*
X555812Y-218821D01*
X556811D01*
X557311Y-218321D01*
X549314Y-216322D02*
X549814Y-215822D01*
X550813D01*
X551313Y-216322D01*
Y-216822D01*
X550813Y-217322D01*
X549814D01*
X549314Y-217821D01*
Y-218321D01*
X549814Y-218821D01*
X550813D01*
X551313Y-218321D01*
X546815Y-218821D02*
X547814D01*
X548314Y-218321D01*
Y-217322D01*
X547814Y-216822D01*
X546815D01*
X546315Y-217322D01*
Y-217821D01*
X548314D01*
X545315Y-218821D02*
X544315D01*
X544815D01*
Y-215822D01*
X545315D01*
X541316Y-218821D02*
X542316D01*
X542816Y-218321D01*
Y-217322D01*
X542316Y-216822D01*
X541316D01*
X540817Y-217322D01*
Y-217821D01*
X542816D01*
X537817Y-216822D02*
X539317D01*
X539817Y-217322D01*
Y-218321D01*
X539317Y-218821D01*
X537817D01*
X536318Y-216322D02*
Y-216822D01*
X536818D01*
X535818D01*
X536318D01*
Y-218321D01*
X535818Y-218821D01*
X563615Y-177490D02*
X564115Y-176991D01*
X565115D01*
X565615Y-177490D01*
Y-179490D01*
X565115Y-179990D01*
X564115D01*
X563615Y-179490D01*
Y-178490D01*
X564615D01*
X562616Y-179990D02*
Y-176991D01*
X561116D01*
X560616Y-177490D01*
Y-178490D01*
X561116Y-178990D01*
X562616D01*
X557617Y-177490D02*
X558117Y-176991D01*
X559117D01*
X559617Y-177490D01*
Y-177990D01*
X559117Y-178490D01*
X558117D01*
X557617Y-178990D01*
Y-179490D01*
X558117Y-179990D01*
X559117D01*
X559617Y-179490D01*
X556618Y-179990D02*
X555618D01*
X556118D01*
Y-176991D01*
X556618Y-177490D01*
X549120D02*
X549620Y-176991D01*
X550620D01*
X551119Y-177490D01*
Y-177990D01*
X550620Y-178490D01*
X549620D01*
X549120Y-178990D01*
Y-179490D01*
X549620Y-179990D01*
X550620D01*
X551119Y-179490D01*
X546621Y-179990D02*
X547620D01*
X548120Y-179490D01*
Y-178490D01*
X547620Y-177990D01*
X546621D01*
X546121Y-178490D01*
Y-178990D01*
X548120D01*
X545121Y-179990D02*
X544122D01*
X544621D01*
Y-176991D01*
X545121D01*
X541123Y-179990D02*
X542122D01*
X542622Y-179490D01*
Y-178490D01*
X542122Y-177990D01*
X541123D01*
X540623Y-178490D01*
Y-178990D01*
X542622D01*
X537624Y-177990D02*
X539123D01*
X539623Y-178490D01*
Y-179490D01*
X539123Y-179990D01*
X537624D01*
X536124Y-177490D02*
Y-177990D01*
X536624D01*
X535624D01*
X536124D01*
Y-179490D01*
X535624Y-179990D01*
X562553Y-167189D02*
X563053Y-166689D01*
X564053D01*
X564552Y-167189D01*
Y-169188D01*
X564053Y-169688D01*
X563053D01*
X562553Y-169188D01*
Y-168189D01*
X563553D01*
X561553Y-169688D02*
Y-166689D01*
X560054D01*
X559554Y-167189D01*
Y-168189D01*
X560054Y-168689D01*
X561553D01*
X556555Y-167189D02*
X557055Y-166689D01*
X558054D01*
X558554Y-167189D01*
Y-167689D01*
X558054Y-168189D01*
X557055D01*
X556555Y-168689D01*
Y-169188D01*
X557055Y-169688D01*
X558054D01*
X558554Y-169188D01*
X553556Y-169688D02*
X555555D01*
X553556Y-167689D01*
Y-167189D01*
X554056Y-166689D01*
X555056D01*
X555555Y-167189D01*
X547558D02*
X548058Y-166689D01*
X549057D01*
X549557Y-167189D01*
Y-167689D01*
X549057Y-168189D01*
X548058D01*
X547558Y-168689D01*
Y-169188D01*
X548058Y-169688D01*
X549057D01*
X549557Y-169188D01*
X545059Y-169688D02*
X546058D01*
X546558Y-169188D01*
Y-168189D01*
X546058Y-167689D01*
X545059D01*
X544559Y-168189D01*
Y-168689D01*
X546558D01*
X543559Y-169688D02*
X542560D01*
X543059D01*
Y-166689D01*
X543559D01*
X539561Y-169688D02*
X540560D01*
X541060Y-169188D01*
Y-168189D01*
X540560Y-167689D01*
X539561D01*
X539061Y-168189D01*
Y-168689D01*
X541060D01*
X536062Y-167689D02*
X537561D01*
X538061Y-168189D01*
Y-169188D01*
X537561Y-169688D01*
X536062D01*
X534562Y-167189D02*
Y-167689D01*
X535062D01*
X534062D01*
X534562D01*
Y-169188D01*
X534062Y-169688D01*
X604067Y-188507D02*
Y-185508D01*
X602568D01*
X602068Y-186008D01*
Y-187008D01*
X602568Y-187508D01*
X604067D01*
X603067D02*
X602068Y-188507D01*
X601068D02*
X600069D01*
X600568D01*
Y-185508D01*
X601068Y-186008D01*
X598569Y-185508D02*
X596570D01*
Y-186008D01*
X598569Y-188007D01*
Y-188507D01*
X595570Y-186008D02*
X595070Y-185508D01*
X594070D01*
X593571Y-186008D01*
Y-186508D01*
X594070Y-187008D01*
X593571Y-187508D01*
Y-188007D01*
X594070Y-188507D01*
X595070D01*
X595570Y-188007D01*
Y-187508D01*
X595070Y-187008D01*
X595570Y-186508D01*
Y-186008D01*
X595070Y-187008D02*
X594070D01*
X592595Y-165378D02*
X595594D01*
Y-163879D01*
X595094Y-163379D01*
X594095D01*
X593595Y-163879D01*
Y-165378D01*
Y-164379D02*
X592595Y-163379D01*
Y-162379D02*
Y-161380D01*
Y-161880D01*
X595594D01*
X595094Y-162379D01*
X592595Y-158381D02*
X595594D01*
X594095Y-159880D01*
Y-157881D01*
X592595Y-156881D02*
Y-155881D01*
Y-156381D01*
X595594D01*
X595094Y-156881D01*
X592595Y-182414D02*
X595594D01*
Y-180914D01*
X595094Y-180414D01*
X594095D01*
X593595Y-180914D01*
Y-182414D01*
Y-181414D02*
X592595Y-180414D01*
Y-179415D02*
Y-178415D01*
Y-178915D01*
X595594D01*
X595094Y-179415D01*
X592595Y-175416D02*
X595594D01*
X594095Y-176915D01*
Y-174916D01*
X595094Y-173916D02*
X595594Y-173417D01*
Y-172417D01*
X595094Y-171917D01*
X593095D01*
X592595Y-172417D01*
Y-173417D01*
X593095Y-173916D01*
X595094D01*
X151363Y-3050D02*
X150863Y-2550D01*
Y-1551D01*
X151363Y-1051D01*
X153362D01*
X153862Y-1551D01*
Y-2550D01*
X153362Y-3050D01*
X153862Y-4050D02*
Y-5050D01*
Y-4550D01*
X150863D01*
X151363Y-4050D01*
Y-6549D02*
X150863Y-7049D01*
Y-8049D01*
X151363Y-8548D01*
X153362D01*
X153862Y-8049D01*
Y-7049D01*
X153362Y-6549D01*
X151363D01*
X153362Y-9548D02*
X153862Y-10048D01*
Y-11048D01*
X153362Y-11547D01*
X151363D01*
X150863Y-11048D01*
Y-10048D01*
X151363Y-9548D01*
X151862D01*
X152362Y-10048D01*
Y-11547D01*
X471048Y-297145D02*
X470548Y-296645D01*
Y-295645D01*
X471048Y-295145D01*
X473047D01*
X473547Y-295645D01*
Y-296645D01*
X473047Y-297145D01*
X473547Y-298144D02*
Y-299144D01*
Y-298644D01*
X470548D01*
X471048Y-298144D01*
Y-300644D02*
X470548Y-301144D01*
Y-302143D01*
X471048Y-302643D01*
X473047D01*
X473547Y-302143D01*
Y-301144D01*
X473047Y-300644D01*
X471048D01*
Y-303643D02*
X470548Y-304142D01*
Y-305142D01*
X471048Y-305642D01*
X471547D01*
X472047Y-305142D01*
X472547Y-305642D01*
X473047D01*
X473547Y-305142D01*
Y-304142D01*
X473047Y-303643D01*
X472547D01*
X472047Y-304142D01*
X471547Y-303643D01*
X471048D01*
X472047Y-304142D02*
Y-305142D01*
X197063Y-97737D02*
X197563Y-98237D01*
Y-99237D01*
X197063Y-99736D01*
X195063D01*
X194563Y-99237D01*
Y-98237D01*
X195063Y-97737D01*
X194563Y-96737D02*
Y-95738D01*
Y-96238D01*
X197563D01*
X197063Y-96737D01*
Y-94238D02*
X197563Y-93738D01*
Y-92739D01*
X197063Y-92239D01*
X195063D01*
X194563Y-92739D01*
Y-93738D01*
X195063Y-94238D01*
X197063D01*
X197563Y-91239D02*
Y-89240D01*
X197063D01*
X195063Y-91239D01*
X194563D01*
X481989Y-258055D02*
X482489Y-257556D01*
X483489D01*
X483989Y-258055D01*
Y-260055D01*
X483489Y-260555D01*
X482489D01*
X481989Y-260055D01*
X480989Y-260555D02*
X479990D01*
X480490D01*
Y-257556D01*
X480989Y-258055D01*
X478490D02*
X477990Y-257556D01*
X476991D01*
X476491Y-258055D01*
Y-260055D01*
X476991Y-260555D01*
X477990D01*
X478490Y-260055D01*
Y-258055D01*
X473492Y-257556D02*
X474492Y-258055D01*
X475491Y-259055D01*
Y-260055D01*
X474991Y-260555D01*
X473992D01*
X473492Y-260055D01*
Y-259555D01*
X473992Y-259055D01*
X475491D01*
X580021Y-254512D02*
X580520Y-254012D01*
X581520D01*
X582020Y-254512D01*
Y-256511D01*
X581520Y-257011D01*
X580520D01*
X580021Y-256511D01*
X579021Y-257011D02*
X578021D01*
X578521D01*
Y-254012D01*
X579021Y-254512D01*
X576522D02*
X576022Y-254012D01*
X575022D01*
X574522Y-254512D01*
Y-256511D01*
X575022Y-257011D01*
X576022D01*
X576522Y-256511D01*
Y-254512D01*
X571523Y-254012D02*
X573523D01*
Y-255512D01*
X572523Y-255012D01*
X572023D01*
X571523Y-255512D01*
Y-256511D01*
X572023Y-257011D01*
X573023D01*
X573523Y-256511D01*
X565896Y-253886D02*
X566396Y-253386D01*
X567396D01*
X567896Y-253886D01*
Y-255886D01*
X567396Y-256385D01*
X566396D01*
X565896Y-255886D01*
X564896Y-256385D02*
X563897D01*
X564397D01*
Y-253386D01*
X564896Y-253886D01*
X562397D02*
X561898Y-253386D01*
X560898D01*
X560398Y-253886D01*
Y-255886D01*
X560898Y-256385D01*
X561898D01*
X562397Y-255886D01*
Y-253886D01*
X557899Y-256385D02*
Y-253386D01*
X559398Y-254886D01*
X557399D01*
X493208Y-266748D02*
X492708Y-267248D01*
X491708D01*
X491208Y-266748D01*
Y-264748D01*
X491708Y-264248D01*
X492708D01*
X493208Y-264748D01*
X494207Y-264248D02*
X495207D01*
X494707D01*
Y-267248D01*
X494207Y-266748D01*
X496707D02*
X497206Y-267248D01*
X498206D01*
X498706Y-266748D01*
Y-264748D01*
X498206Y-264248D01*
X497206D01*
X496707Y-264748D01*
Y-266748D01*
X499706D02*
X500206Y-267248D01*
X501205D01*
X501705Y-266748D01*
Y-266248D01*
X501205Y-265748D01*
X500705D01*
X501205D01*
X501705Y-265248D01*
Y-264748D01*
X501205Y-264248D01*
X500206D01*
X499706Y-264748D01*
X520178Y-259630D02*
X520678Y-259130D01*
X521678D01*
X522177Y-259630D01*
Y-261630D01*
X521678Y-262129D01*
X520678D01*
X520178Y-261630D01*
X519178Y-262129D02*
X518179D01*
X518679D01*
Y-259130D01*
X519178Y-259630D01*
X516679D02*
X516179Y-259130D01*
X515180D01*
X514680Y-259630D01*
Y-261630D01*
X515180Y-262129D01*
X516179D01*
X516679Y-261630D01*
Y-259630D01*
X511681Y-262129D02*
X513680D01*
X511681Y-260130D01*
Y-259630D01*
X512181Y-259130D01*
X513180D01*
X513680Y-259630D01*
X491332Y-253331D02*
X491832Y-252831D01*
X492831D01*
X493331Y-253331D01*
Y-255330D01*
X492831Y-255830D01*
X491832D01*
X491332Y-255330D01*
X490332Y-255830D02*
X489332D01*
X489832D01*
Y-252831D01*
X490332Y-253331D01*
X487833D02*
X487333Y-252831D01*
X486333D01*
X485834Y-253331D01*
Y-255330D01*
X486333Y-255830D01*
X487333D01*
X487833Y-255330D01*
Y-253331D01*
X484834Y-255830D02*
X483834D01*
X484334D01*
Y-252831D01*
X484834Y-253331D01*
X213624Y-82127D02*
X213124Y-81627D01*
Y-80628D01*
X213624Y-80128D01*
X215624D01*
X216124Y-80628D01*
Y-81627D01*
X215624Y-82127D01*
X216124Y-83127D02*
Y-84126D01*
Y-83627D01*
X213124D01*
X213624Y-83127D01*
Y-85626D02*
X213124Y-86126D01*
Y-87125D01*
X213624Y-87625D01*
X215624D01*
X216124Y-87125D01*
Y-86126D01*
X215624Y-85626D01*
X213624D01*
Y-88625D02*
X213124Y-89125D01*
Y-90124D01*
X213624Y-90624D01*
X215624D01*
X216124Y-90124D01*
Y-89125D01*
X215624Y-88625D01*
X213624D01*
X202150Y-82253D02*
X201650Y-81753D01*
Y-80753D01*
X202150Y-80253D01*
X204149D01*
X204649Y-80753D01*
Y-81753D01*
X204149Y-82253D01*
Y-83252D02*
X204649Y-83752D01*
Y-84752D01*
X204149Y-85252D01*
X202150D01*
X201650Y-84752D01*
Y-83752D01*
X202150Y-83252D01*
X202650D01*
X203150Y-83752D01*
Y-85252D01*
X204149Y-86251D02*
X204649Y-86751D01*
Y-87751D01*
X204149Y-88251D01*
X202150D01*
X201650Y-87751D01*
Y-86751D01*
X202150Y-86251D01*
X202650D01*
X203150Y-86751D01*
Y-88251D01*
X215491Y8737D02*
X214991Y9237D01*
Y10237D01*
X215491Y10736D01*
X217490D01*
X217990Y10237D01*
Y9237D01*
X217490Y8737D01*
Y7737D02*
X217990Y7237D01*
Y6238D01*
X217490Y5738D01*
X215491D01*
X214991Y6238D01*
Y7237D01*
X215491Y7737D01*
X215991D01*
X216491Y7237D01*
Y5738D01*
X215491Y4738D02*
X214991Y4239D01*
Y3239D01*
X215491Y2739D01*
X215991D01*
X216491Y3239D01*
X216990Y2739D01*
X217490D01*
X217990Y3239D01*
Y4239D01*
X217490Y4738D01*
X216990D01*
X216491Y4239D01*
X215991Y4738D01*
X215491D01*
X216491Y4239D02*
Y3239D01*
X202150Y9086D02*
X201650Y9586D01*
Y10586D01*
X202150Y11085D01*
X204149D01*
X204649Y10586D01*
Y9586D01*
X204149Y9086D01*
Y8086D02*
X204649Y7586D01*
Y6587D01*
X204149Y6087D01*
X202150D01*
X201650Y6587D01*
Y7586D01*
X202150Y8086D01*
X202650D01*
X203150Y7586D01*
Y6087D01*
X201650Y5087D02*
Y3088D01*
X202150D01*
X204149Y5087D01*
X204649D01*
X208449Y15385D02*
X207949Y15885D01*
Y16885D01*
X208449Y17384D01*
X210449D01*
X210948Y16885D01*
Y15885D01*
X210449Y15385D01*
X207949Y14386D02*
Y12386D01*
X208449D01*
X210449Y14386D01*
X210948D01*
Y9887D02*
X207949D01*
X209449Y11387D01*
Y9387D01*
X548555Y-247563D02*
Y-244564D01*
X547056D01*
X546556Y-245063D01*
Y-246063D01*
X547056Y-246563D01*
X548555D01*
X547556D02*
X546556Y-247563D01*
X545556D02*
X544557D01*
X545056D01*
Y-244564D01*
X545556Y-245063D01*
X543057D02*
X542557Y-244564D01*
X541558D01*
X541058Y-245063D01*
Y-245563D01*
X541558Y-246063D01*
X542058D01*
X541558D01*
X541058Y-246563D01*
Y-247063D01*
X541558Y-247563D01*
X542557D01*
X543057Y-247063D01*
X540058Y-244564D02*
X538059D01*
Y-245063D01*
X540058Y-247063D01*
Y-247563D01*
X551311Y-252287D02*
Y-249288D01*
X549812D01*
X549312Y-249788D01*
Y-250787D01*
X549812Y-251287D01*
X551311D01*
X550312D02*
X549312Y-252287D01*
X548312D02*
X547313D01*
X547812D01*
Y-249288D01*
X548312Y-249788D01*
X545813D02*
X545313Y-249288D01*
X544314D01*
X543814Y-249788D01*
Y-250288D01*
X544314Y-250787D01*
X544813D01*
X544314D01*
X543814Y-251287D01*
Y-251787D01*
X544314Y-252287D01*
X545313D01*
X545813Y-251787D01*
X540815Y-249288D02*
X541814Y-249788D01*
X542814Y-250787D01*
Y-251787D01*
X542314Y-252287D01*
X541315D01*
X540815Y-251787D01*
Y-251287D01*
X541315Y-250787D01*
X542814D01*
X530445Y-257405D02*
Y-254406D01*
X528946D01*
X528446Y-254906D01*
Y-255906D01*
X528946Y-256405D01*
X530445D01*
X529446D02*
X528446Y-257405D01*
X527446D02*
X526446D01*
X526946D01*
Y-254406D01*
X527446Y-254906D01*
X524947D02*
X524447Y-254406D01*
X523447D01*
X522948Y-254906D01*
Y-255406D01*
X523447Y-255906D01*
X523947D01*
X523447D01*
X522948Y-256405D01*
Y-256905D01*
X523447Y-257405D01*
X524447D01*
X524947Y-256905D01*
X519948Y-254406D02*
X521948D01*
Y-255906D01*
X520948Y-255406D01*
X520448D01*
X519948Y-255906D01*
Y-256905D01*
X520448Y-257405D01*
X521448D01*
X521948Y-256905D01*
X222671Y-19457D02*
X219672D01*
Y-20956D01*
X220172Y-21456D01*
X221171D01*
X221671Y-20956D01*
Y-19457D01*
Y-20457D02*
X222671Y-21456D01*
Y-22456D02*
Y-23456D01*
Y-22956D01*
X219672D01*
X220172Y-22456D01*
Y-24955D02*
X219672Y-25455D01*
Y-26454D01*
X220172Y-26954D01*
X220672D01*
X221171Y-26454D01*
Y-25955D01*
Y-26454D01*
X221671Y-26954D01*
X222171D01*
X222671Y-26454D01*
Y-25455D01*
X222171Y-24955D01*
X222671Y-29454D02*
X219672D01*
X221171Y-27954D01*
Y-29953D01*
X216854Y-21523D02*
X213855D01*
Y-23023D01*
X214355Y-23523D01*
X215354D01*
X215854Y-23023D01*
Y-21523D01*
Y-22523D02*
X216854Y-23523D01*
Y-24522D02*
Y-25522D01*
Y-25022D01*
X213855D01*
X214355Y-24522D01*
Y-27022D02*
X213855Y-27521D01*
Y-28521D01*
X214355Y-29021D01*
X214855D01*
X215354Y-28521D01*
Y-28021D01*
Y-28521D01*
X215854Y-29021D01*
X216354D01*
X216854Y-28521D01*
Y-27521D01*
X216354Y-27022D01*
X214355Y-30021D02*
X213855Y-30520D01*
Y-31520D01*
X214355Y-32020D01*
X214855D01*
X215354Y-31520D01*
Y-31020D01*
Y-31520D01*
X215854Y-32020D01*
X216354D01*
X216854Y-31520D01*
Y-30520D01*
X216354Y-30021D01*
X205830Y-33728D02*
X202831D01*
Y-35228D01*
X203331Y-35727D01*
X204331D01*
X204831Y-35228D01*
Y-33728D01*
Y-34728D02*
X205830Y-35727D01*
Y-36727D02*
Y-37727D01*
Y-37227D01*
X202831D01*
X203331Y-36727D01*
Y-39226D02*
X202831Y-39726D01*
Y-40726D01*
X203331Y-41226D01*
X203831D01*
X204331Y-40726D01*
Y-40226D01*
Y-40726D01*
X204831Y-41226D01*
X205330D01*
X205830Y-40726D01*
Y-39726D01*
X205330Y-39226D01*
X205830Y-44225D02*
Y-42225D01*
X203831Y-44225D01*
X203331D01*
X202831Y-43725D01*
Y-42725D01*
X203331Y-42225D01*
X446630Y-149343D02*
X449629D01*
Y-147843D01*
X449130Y-147343D01*
X448130D01*
X447630Y-147843D01*
Y-149343D01*
Y-148343D02*
X446630Y-147343D01*
Y-146344D02*
Y-145344D01*
Y-145844D01*
X449629D01*
X449130Y-146344D01*
X446630Y-141845D02*
Y-143845D01*
X448630Y-141845D01*
X449130D01*
X449629Y-142345D01*
Y-143345D01*
X449130Y-143845D01*
X447130Y-140846D02*
X446630Y-140346D01*
Y-139346D01*
X447130Y-138846D01*
X449130D01*
X449629Y-139346D01*
Y-140346D01*
X449130Y-140846D01*
X448630D01*
X448130Y-140346D01*
Y-138846D01*
X435495Y-107011D02*
Y-104012D01*
X433995D01*
X433495Y-104512D01*
Y-105512D01*
X433995Y-106012D01*
X435495D01*
X434495D02*
X433495Y-107011D01*
X430496Y-104012D02*
X431496Y-104512D01*
X432496Y-105512D01*
Y-106511D01*
X431996Y-107011D01*
X430996D01*
X430496Y-106511D01*
Y-106012D01*
X430996Y-105512D01*
X432496D01*
X429497Y-106511D02*
X428997Y-107011D01*
X427997D01*
X427497Y-106511D01*
Y-104512D01*
X427997Y-104012D01*
X428997D01*
X429497Y-104512D01*
Y-105012D01*
X428997Y-105512D01*
X427497D01*
X593382Y-231233D02*
X596381D01*
Y-229733D01*
X595882Y-229233D01*
X594882D01*
X594382Y-229733D01*
Y-231233D01*
Y-230233D02*
X593382Y-229233D01*
Y-228234D02*
Y-227234D01*
Y-227734D01*
X596381D01*
X595882Y-228234D01*
X593382Y-223735D02*
Y-225734D01*
X595382Y-223735D01*
X595882D01*
X596381Y-224235D01*
Y-225235D01*
X595882Y-225734D01*
X596381Y-220736D02*
Y-222735D01*
X594882D01*
X595382Y-221736D01*
Y-221236D01*
X594882Y-220736D01*
X593882D01*
X593382Y-221236D01*
Y-222235D01*
X593882Y-222735D01*
X581027Y-224279D02*
X578028D01*
Y-225779D01*
X578528Y-226279D01*
X579528D01*
X580027Y-225779D01*
Y-224279D01*
Y-225279D02*
X581027Y-226279D01*
Y-227278D02*
Y-228278D01*
Y-227778D01*
X578028D01*
X578528Y-227278D01*
X581027Y-231777D02*
Y-229778D01*
X579028Y-231777D01*
X578528D01*
X578028Y-231277D01*
Y-230277D01*
X578528Y-229778D01*
X581027Y-234776D02*
Y-232776D01*
X579028Y-234776D01*
X578528D01*
X578028Y-234276D01*
Y-233276D01*
X578528Y-232776D01*
X578271Y-237128D02*
X575272D01*
Y-238627D01*
X575772Y-239127D01*
X576772D01*
X577272Y-238627D01*
Y-237128D01*
Y-238127D02*
X578271Y-239127D01*
Y-240127D02*
Y-241126D01*
Y-240627D01*
X575272D01*
X575772Y-240127D01*
X578271Y-242626D02*
Y-243625D01*
Y-243126D01*
X575272D01*
X575772Y-242626D01*
X578271Y-247124D02*
Y-245125D01*
X576272Y-247124D01*
X575772D01*
X575272Y-246624D01*
Y-245625D01*
X575772Y-245125D01*
D290*
X149213Y-259498D02*
D03*
M02*
